FILE_TYPE = MACRO_DRAWING;
SET COLOR_WIRE YELLOW;
SET COLOR_PROP ORANGE;
SET COLOR_DOT WHITE;
SET COLOR_ARC YELLOW;
SET COLOR_BODY GREEN;
SET COLOR_NOTE PURPLE;
SET PROP_DISPLAY VALUE;
SET PAGE_NUMBER P55;
FORCEADD OFFPAGE..2
R 2
(-2100 -50);
FORCEPROP 2 LAST $XR1 107 
J 0
(-2475 -50);
DISPLAY 0.638298 (-2475 -50);
PAINT MONO (-2475 -50);
FORCEPROP 2 LAST $XR0 106 
J 0
(-2355 -50);
DISPLAY 0.638298 (-2355 -50);
PAINT MONO (-2355 -50);
FORCEPROP 2 LAST CDS_LIB standard
J 0
(-2100 -50);
PAINT MONO (-2100 -50);
DISPLAY INVISIBLE (-2100 -50);
FORCEPROP 1 LAST OFFPAGE TRUE
J 2
(-2425 -175);
DISPLAY 0.872340 (-2425 -175);
DISPLAY INVISIBLE (-2425 -175);
FORCEPROP 1 LAST COMMENT_BODY TRUE
J 2
(-2055 -145);
DISPLAY 0.872340 (-2055 -145);
PAINT GREEN (-2055 -145);
DISPLAY INVISIBLE (-2055 -145);
FORCEPROP 2 LAST PATH I1
J 0
(-2050 25);
DISPLAY 1.021277 (-2050 25);
DISPLAY INVISIBLE (-2050 25);
FORCEADD TAP..1
R 2
(-1075 25);
FORCEPROP 3 LASTPIN (-1025 25) SIG_NAME M_E_CPU1_SB_CB<0>
J 0
(-1015 35);
DISPLAY 0.659574 (-1015 35);
PAINT MONO (-1015 35);
DISPLAY INVISIBLE (-1015 35);
FORCEPROP 1 LASTPIN (-1025 25) BN 0
J 2
(-1013 33);
DISPLAY 0.680851 (-1013 33);
PAINT GREEN (-1013 33);
FORCEPROP 2 LAST CDS_LIB standard
J 0
(-1075 25);
DISPLAY INVISIBLE (-1075 25);
FORCEPROP 1 LAST BODY_TYPE PLUMBING
J 2
(-1075 75);
DISPLAY 0.872340 (-1075 75);
PAINT GREEN (-1075 75);
DISPLAY INVISIBLE (-1075 75);
FORCEPROP 1 LAST HDL_TAP TRUE
J 2
(-1400 -100);
DISPLAY 0.872340 (-1400 -100);
DISPLAY INVISIBLE (-1400 -100);
FORCEPROP 1 LAST PATH I10
J 2
(-1073 25);
DISPLAY 0.872340 (-1073 25);
PAINT GREEN (-1073 25);
DISPLAY INVISIBLE (-1073 25);
FORCEADD TAP..1
(2350 675);
FORCEPROP 3 LASTPIN (2300 675) SIG_NAME M_E_CPU1_SA_CS_N<3>
J 0
(2310 685);
DISPLAY 0.659574 (2310 685);
PAINT MONO (2310 685);
DISPLAY INVISIBLE (2310 685);
FORCEPROP 1 LASTPIN (2300 675) BN 3
J 0
(2288 683);
DISPLAY 0.680851 (2288 683);
PAINT GREEN (2288 683);
FORCEPROP 2 LAST CDS_LIB standard
J 0
(2350 675);
DISPLAY INVISIBLE (2350 675);
FORCEPROP 1 LAST BODY_TYPE PLUMBING
J 0
(2350 725);
DISPLAY 0.872340 (2350 725);
PAINT GREEN (2350 725);
DISPLAY INVISIBLE (2350 725);
FORCEPROP 1 LAST HDL_TAP TRUE
J 0
(2675 550);
DISPLAY 0.872340 (2675 550);
DISPLAY INVISIBLE (2675 550);
FORCEPROP 1 LAST PATH I100
J 0
(2348 675);
DISPLAY 0.872340 (2348 675);
PAINT GREEN (2348 675);
DISPLAY INVISIBLE (2348 675);
FORCEADD TAP..1
(2350 525);
FORCEPROP 3 LASTPIN (2300 525) SIG_NAME M_E_CPU1_SA_CS_N<0>
J 0
(2310 535);
DISPLAY 0.659574 (2310 535);
PAINT MONO (2310 535);
DISPLAY INVISIBLE (2310 535);
FORCEPROP 1 LASTPIN (2300 525) BN 0
J 0
(2288 533);
DISPLAY 0.680851 (2288 533);
PAINT GREEN (2288 533);
FORCEPROP 2 LAST CDS_LIB standard
J 0
(2350 525);
DISPLAY INVISIBLE (2350 525);
FORCEPROP 1 LAST BODY_TYPE PLUMBING
J 0
(2350 575);
DISPLAY 0.872340 (2350 575);
PAINT GREEN (2350 575);
DISPLAY INVISIBLE (2350 575);
FORCEPROP 1 LAST HDL_TAP TRUE
J 0
(2675 400);
DISPLAY 0.872340 (2675 400);
DISPLAY INVISIBLE (2675 400);
FORCEPROP 1 LAST PATH I101
J 0
(2348 525);
DISPLAY 0.872340 (2348 525);
PAINT GREEN (2348 525);
DISPLAY INVISIBLE (2348 525);
FORCEADD TAP..1
(2350 575);
FORCEPROP 3 LASTPIN (2300 575) SIG_NAME M_E_CPU1_SA_CS_N<1>
J 0
(2310 585);
DISPLAY 0.659574 (2310 585);
PAINT MONO (2310 585);
DISPLAY INVISIBLE (2310 585);
FORCEPROP 1 LASTPIN (2300 575) BN 1
J 0
(2288 583);
DISPLAY 0.680851 (2288 583);
PAINT GREEN (2288 583);
FORCEPROP 2 LAST CDS_LIB standard
J 0
(2350 575);
DISPLAY INVISIBLE (2350 575);
FORCEPROP 1 LAST BODY_TYPE PLUMBING
J 0
(2350 625);
DISPLAY 0.872340 (2350 625);
PAINT GREEN (2350 625);
DISPLAY INVISIBLE (2350 625);
FORCEPROP 1 LAST HDL_TAP TRUE
J 0
(2675 450);
DISPLAY 0.872340 (2675 450);
DISPLAY INVISIBLE (2675 450);
FORCEPROP 1 LAST PATH I102
J 0
(2348 575);
DISPLAY 0.872340 (2348 575);
PAINT GREEN (2348 575);
DISPLAY INVISIBLE (2348 575);
FORCEADD TAP..1
(2350 925);
FORCEPROP 3 LASTPIN (2300 925) SIG_NAME M_E_CPU1_SB_CA<1>
J 0
(2310 935);
DISPLAY 0.659574 (2310 935);
PAINT MONO (2310 935);
DISPLAY INVISIBLE (2310 935);
FORCEPROP 1 LASTPIN (2300 925) BN 1
J 0
(2288 933);
DISPLAY 0.680851 (2288 933);
PAINT GREEN (2288 933);
FORCEPROP 2 LAST CDS_LIB standard
J 0
(2350 925);
DISPLAY INVISIBLE (2350 925);
FORCEPROP 1 LAST BODY_TYPE PLUMBING
J 0
(2350 975);
DISPLAY 0.872340 (2350 975);
PAINT GREEN (2350 975);
DISPLAY INVISIBLE (2350 975);
FORCEPROP 1 LAST HDL_TAP TRUE
J 0
(2675 800);
DISPLAY 0.872340 (2675 800);
DISPLAY INVISIBLE (2675 800);
FORCEPROP 1 LAST PATH I103
J 0
(2348 925);
DISPLAY 0.872340 (2348 925);
PAINT GREEN (2348 925);
DISPLAY INVISIBLE (2348 925);
FORCEADD TAP..1
(2350 875);
FORCEPROP 3 LASTPIN (2300 875) SIG_NAME M_E_CPU1_SB_CA<0>
J 0
(2310 885);
DISPLAY 0.659574 (2310 885);
PAINT MONO (2310 885);
DISPLAY INVISIBLE (2310 885);
FORCEPROP 1 LASTPIN (2300 875) BN 0
J 0
(2288 883);
DISPLAY 0.680851 (2288 883);
PAINT GREEN (2288 883);
FORCEPROP 2 LAST CDS_LIB standard
J 0
(2350 875);
DISPLAY INVISIBLE (2350 875);
FORCEPROP 1 LAST BODY_TYPE PLUMBING
J 0
(2350 925);
DISPLAY 0.872340 (2350 925);
PAINT GREEN (2350 925);
DISPLAY INVISIBLE (2350 925);
FORCEPROP 1 LAST HDL_TAP TRUE
J 0
(2675 750);
DISPLAY 0.872340 (2675 750);
DISPLAY INVISIBLE (2675 750);
FORCEPROP 1 LAST PATH I104
J 0
(2348 875);
DISPLAY 0.872340 (2348 875);
PAINT GREEN (2348 875);
DISPLAY INVISIBLE (2348 875);
FORCEADD TAP..1
(2350 975);
FORCEPROP 3 LASTPIN (2300 975) SIG_NAME M_E_CPU1_SB_CA<2>
J 0
(2310 985);
DISPLAY 0.659574 (2310 985);
PAINT MONO (2310 985);
DISPLAY INVISIBLE (2310 985);
FORCEPROP 1 LASTPIN (2300 975) BN 2
J 0
(2288 983);
DISPLAY 0.680851 (2288 983);
PAINT GREEN (2288 983);
FORCEPROP 2 LAST CDS_LIB standard
J 0
(2350 975);
DISPLAY INVISIBLE (2350 975);
FORCEPROP 1 LAST BODY_TYPE PLUMBING
J 0
(2350 1025);
DISPLAY 0.872340 (2350 1025);
PAINT GREEN (2350 1025);
DISPLAY INVISIBLE (2350 1025);
FORCEPROP 1 LAST HDL_TAP TRUE
J 0
(2675 850);
DISPLAY 0.872340 (2675 850);
DISPLAY INVISIBLE (2675 850);
FORCEPROP 1 LAST PATH I105
J 0
(2348 975);
DISPLAY 0.872340 (2348 975);
PAINT GREEN (2348 975);
DISPLAY INVISIBLE (2348 975);
FORCEADD TAP..1
(2350 1175);
FORCEPROP 3 LASTPIN (2300 1175) SIG_NAME M_E_CPU1_SB_CA<6>
J 0
(2310 1185);
DISPLAY 0.659574 (2310 1185);
PAINT MONO (2310 1185);
DISPLAY INVISIBLE (2310 1185);
FORCEPROP 1 LASTPIN (2300 1175) BN 6
J 0
(2288 1183);
DISPLAY 0.680851 (2288 1183);
PAINT GREEN (2288 1183);
FORCEPROP 2 LAST CDS_LIB standard
J 0
(2350 1175);
DISPLAY INVISIBLE (2350 1175);
FORCEPROP 1 LAST BODY_TYPE PLUMBING
J 0
(2350 1225);
DISPLAY 0.872340 (2350 1225);
PAINT GREEN (2350 1225);
DISPLAY INVISIBLE (2350 1225);
FORCEPROP 1 LAST HDL_TAP TRUE
J 0
(2675 1050);
DISPLAY 0.872340 (2675 1050);
DISPLAY INVISIBLE (2675 1050);
FORCEPROP 1 LAST PATH I106
J 0
(2348 1175);
DISPLAY 0.872340 (2348 1175);
PAINT GREEN (2348 1175);
DISPLAY INVISIBLE (2348 1175);
FORCEADD TAP..1
(2350 1125);
FORCEPROP 3 LASTPIN (2300 1125) SIG_NAME M_E_CPU1_SB_CA<5>
J 0
(2310 1135);
DISPLAY 0.659574 (2310 1135);
PAINT MONO (2310 1135);
DISPLAY INVISIBLE (2310 1135);
FORCEPROP 1 LASTPIN (2300 1125) BN 5
J 0
(2288 1133);
DISPLAY 0.680851 (2288 1133);
PAINT GREEN (2288 1133);
FORCEPROP 2 LAST CDS_LIB standard
J 0
(2350 1125);
DISPLAY INVISIBLE (2350 1125);
FORCEPROP 1 LAST BODY_TYPE PLUMBING
J 0
(2350 1175);
DISPLAY 0.872340 (2350 1175);
PAINT GREEN (2350 1175);
DISPLAY INVISIBLE (2350 1175);
FORCEPROP 1 LAST HDL_TAP TRUE
J 0
(2675 1000);
DISPLAY 0.872340 (2675 1000);
DISPLAY INVISIBLE (2675 1000);
FORCEPROP 1 LAST PATH I107
J 0
(2348 1125);
DISPLAY 0.872340 (2348 1125);
PAINT GREEN (2348 1125);
DISPLAY INVISIBLE (2348 1125);
FORCEADD TAP..1
(2350 1075);
FORCEPROP 3 LASTPIN (2300 1075) SIG_NAME M_E_CPU1_SB_CA<4>
J 0
(2310 1085);
DISPLAY 0.659574 (2310 1085);
PAINT MONO (2310 1085);
DISPLAY INVISIBLE (2310 1085);
FORCEPROP 1 LASTPIN (2300 1075) BN 4
J 0
(2288 1083);
DISPLAY 0.680851 (2288 1083);
PAINT GREEN (2288 1083);
FORCEPROP 2 LAST CDS_LIB standard
J 0
(2350 1075);
DISPLAY INVISIBLE (2350 1075);
FORCEPROP 1 LAST BODY_TYPE PLUMBING
J 0
(2350 1125);
DISPLAY 0.872340 (2350 1125);
PAINT GREEN (2350 1125);
DISPLAY INVISIBLE (2350 1125);
FORCEPROP 1 LAST HDL_TAP TRUE
J 0
(2675 950);
DISPLAY 0.872340 (2675 950);
DISPLAY INVISIBLE (2675 950);
FORCEPROP 1 LAST PATH I108
J 0
(2348 1075);
DISPLAY 0.872340 (2348 1075);
PAINT GREEN (2348 1075);
DISPLAY INVISIBLE (2348 1075);
FORCEADD TAP..1
(2350 1025);
FORCEPROP 3 LASTPIN (2300 1025) SIG_NAME M_E_CPU1_SB_CA<3>
J 0
(2310 1035);
DISPLAY 0.659574 (2310 1035);
PAINT MONO (2310 1035);
DISPLAY INVISIBLE (2310 1035);
FORCEPROP 1 LASTPIN (2300 1025) BN 3
J 0
(2288 1033);
DISPLAY 0.680851 (2288 1033);
PAINT GREEN (2288 1033);
FORCEPROP 2 LAST CDS_LIB standard
J 0
(2350 1025);
DISPLAY INVISIBLE (2350 1025);
FORCEPROP 1 LAST BODY_TYPE PLUMBING
J 0
(2350 1075);
DISPLAY 0.872340 (2350 1075);
PAINT GREEN (2350 1075);
DISPLAY INVISIBLE (2350 1075);
FORCEPROP 1 LAST HDL_TAP TRUE
J 0
(2675 900);
DISPLAY 0.872340 (2675 900);
DISPLAY INVISIBLE (2675 900);
FORCEPROP 1 LAST PATH I109
J 0
(2348 1025);
DISPLAY 0.872340 (2348 1025);
PAINT GREEN (2348 1025);
DISPLAY INVISIBLE (2348 1025);
FORCEADD TAP..1
R 2
(-1075 75);
FORCEPROP 3 LASTPIN (-1025 75) SIG_NAME M_E_CPU1_SB_CB<1>
J 0
(-1015 85);
DISPLAY 0.659574 (-1015 85);
PAINT MONO (-1015 85);
DISPLAY INVISIBLE (-1015 85);
FORCEPROP 1 LASTPIN (-1025 75) BN 1
J 2
(-1013 83);
DISPLAY 0.680851 (-1013 83);
PAINT GREEN (-1013 83);
FORCEPROP 2 LAST CDS_LIB standard
J 0
(-1075 75);
DISPLAY INVISIBLE (-1075 75);
FORCEPROP 1 LAST BODY_TYPE PLUMBING
J 2
(-1075 125);
DISPLAY 0.872340 (-1075 125);
PAINT GREEN (-1075 125);
DISPLAY INVISIBLE (-1075 125);
FORCEPROP 1 LAST HDL_TAP TRUE
J 2
(-1400 -50);
DISPLAY 0.872340 (-1400 -50);
DISPLAY INVISIBLE (-1400 -50);
FORCEPROP 1 LAST PATH I11
J 2
(-1073 75);
DISPLAY 0.872340 (-1073 75);
PAINT GREEN (-1073 75);
DISPLAY INVISIBLE (-1073 75);
FORCEADD TAP..1
(2350 1375);
FORCEPROP 3 LASTPIN (2300 1375) SIG_NAME M_E_CPU1_SA_CA<0>
J 0
(2310 1385);
DISPLAY 0.659574 (2310 1385);
PAINT MONO (2310 1385);
DISPLAY INVISIBLE (2310 1385);
FORCEPROP 1 LASTPIN (2300 1375) BN 0
J 0
(2288 1383);
DISPLAY 0.680851 (2288 1383);
PAINT GREEN (2288 1383);
FORCEPROP 2 LAST CDS_LIB standard
J 0
(2350 1375);
DISPLAY INVISIBLE (2350 1375);
FORCEPROP 1 LAST BODY_TYPE PLUMBING
J 0
(2350 1425);
DISPLAY 0.872340 (2350 1425);
PAINT GREEN (2350 1425);
DISPLAY INVISIBLE (2350 1425);
FORCEPROP 1 LAST HDL_TAP TRUE
J 0
(2675 1250);
DISPLAY 0.872340 (2675 1250);
DISPLAY INVISIBLE (2675 1250);
FORCEPROP 1 LAST PATH I110
J 0
(2348 1375);
DISPLAY 0.872340 (2348 1375);
PAINT GREEN (2348 1375);
DISPLAY INVISIBLE (2348 1375);
FORCEADD TAP..1
(2350 1425);
FORCEPROP 3 LASTPIN (2300 1425) SIG_NAME M_E_CPU1_SA_CA<1>
J 0
(2310 1435);
DISPLAY 0.659574 (2310 1435);
PAINT MONO (2310 1435);
DISPLAY INVISIBLE (2310 1435);
FORCEPROP 1 LASTPIN (2300 1425) BN 1
J 0
(2288 1433);
DISPLAY 0.680851 (2288 1433);
PAINT GREEN (2288 1433);
FORCEPROP 2 LAST CDS_LIB standard
J 0
(2350 1425);
DISPLAY INVISIBLE (2350 1425);
FORCEPROP 1 LAST BODY_TYPE PLUMBING
J 0
(2350 1475);
DISPLAY 0.872340 (2350 1475);
PAINT GREEN (2350 1475);
DISPLAY INVISIBLE (2350 1475);
FORCEPROP 1 LAST HDL_TAP TRUE
J 0
(2675 1300);
DISPLAY 0.872340 (2675 1300);
DISPLAY INVISIBLE (2675 1300);
FORCEPROP 1 LAST PATH I111
J 0
(2348 1425);
DISPLAY 0.872340 (2348 1425);
PAINT GREEN (2348 1425);
DISPLAY INVISIBLE (2348 1425);
FORCEADD TAP..1
(2350 1475);
FORCEPROP 3 LASTPIN (2300 1475) SIG_NAME M_E_CPU1_SA_CA<2>
J 0
(2310 1485);
DISPLAY 0.659574 (2310 1485);
PAINT MONO (2310 1485);
DISPLAY INVISIBLE (2310 1485);
FORCEPROP 1 LASTPIN (2300 1475) BN 2
J 0
(2288 1483);
DISPLAY 0.680851 (2288 1483);
PAINT GREEN (2288 1483);
FORCEPROP 2 LAST CDS_LIB standard
J 0
(2350 1475);
DISPLAY INVISIBLE (2350 1475);
FORCEPROP 1 LAST BODY_TYPE PLUMBING
J 0
(2350 1525);
DISPLAY 0.872340 (2350 1525);
PAINT GREEN (2350 1525);
DISPLAY INVISIBLE (2350 1525);
FORCEPROP 1 LAST HDL_TAP TRUE
J 0
(2675 1350);
DISPLAY 0.872340 (2675 1350);
DISPLAY INVISIBLE (2675 1350);
FORCEPROP 1 LAST PATH I112
J 0
(2348 1475);
DISPLAY 0.872340 (2348 1475);
PAINT GREEN (2348 1475);
DISPLAY INVISIBLE (2348 1475);
FORCEADD TAP..1
(2350 1675);
FORCEPROP 3 LASTPIN (2300 1675) SIG_NAME M_E_CPU1_SA_CA<6>
J 0
(2310 1685);
DISPLAY 0.659574 (2310 1685);
PAINT MONO (2310 1685);
DISPLAY INVISIBLE (2310 1685);
FORCEPROP 1 LASTPIN (2300 1675) BN 6
J 0
(2288 1683);
DISPLAY 0.680851 (2288 1683);
PAINT GREEN (2288 1683);
FORCEPROP 2 LAST CDS_LIB standard
J 0
(2350 1675);
DISPLAY INVISIBLE (2350 1675);
FORCEPROP 1 LAST BODY_TYPE PLUMBING
J 0
(2350 1725);
DISPLAY 0.872340 (2350 1725);
PAINT GREEN (2350 1725);
DISPLAY INVISIBLE (2350 1725);
FORCEPROP 1 LAST HDL_TAP TRUE
J 0
(2675 1550);
DISPLAY 0.872340 (2675 1550);
DISPLAY INVISIBLE (2675 1550);
FORCEPROP 1 LAST PATH I113
J 0
(2348 1675);
DISPLAY 0.872340 (2348 1675);
PAINT GREEN (2348 1675);
DISPLAY INVISIBLE (2348 1675);
FORCEADD TAP..1
(2350 1625);
FORCEPROP 3 LASTPIN (2300 1625) SIG_NAME M_E_CPU1_SA_CA<5>
J 0
(2310 1635);
DISPLAY 0.659574 (2310 1635);
PAINT MONO (2310 1635);
DISPLAY INVISIBLE (2310 1635);
FORCEPROP 1 LASTPIN (2300 1625) BN 5
J 0
(2288 1633);
DISPLAY 0.680851 (2288 1633);
PAINT GREEN (2288 1633);
FORCEPROP 2 LAST CDS_LIB standard
J 0
(2350 1625);
DISPLAY INVISIBLE (2350 1625);
FORCEPROP 1 LAST BODY_TYPE PLUMBING
J 0
(2350 1675);
DISPLAY 0.872340 (2350 1675);
PAINT GREEN (2350 1675);
DISPLAY INVISIBLE (2350 1675);
FORCEPROP 1 LAST HDL_TAP TRUE
J 0
(2675 1500);
DISPLAY 0.872340 (2675 1500);
DISPLAY INVISIBLE (2675 1500);
FORCEPROP 1 LAST PATH I114
J 0
(2348 1625);
DISPLAY 0.872340 (2348 1625);
PAINT GREEN (2348 1625);
DISPLAY INVISIBLE (2348 1625);
FORCEADD TAP..1
(2350 1525);
FORCEPROP 3 LASTPIN (2300 1525) SIG_NAME M_E_CPU1_SA_CA<3>
J 0
(2310 1535);
DISPLAY 0.659574 (2310 1535);
PAINT MONO (2310 1535);
DISPLAY INVISIBLE (2310 1535);
FORCEPROP 1 LASTPIN (2300 1525) BN 3
J 0
(2288 1533);
DISPLAY 0.680851 (2288 1533);
PAINT GREEN (2288 1533);
FORCEPROP 2 LAST CDS_LIB standard
J 0
(2350 1525);
DISPLAY INVISIBLE (2350 1525);
FORCEPROP 1 LAST BODY_TYPE PLUMBING
J 0
(2350 1575);
DISPLAY 0.872340 (2350 1575);
PAINT GREEN (2350 1575);
DISPLAY INVISIBLE (2350 1575);
FORCEPROP 1 LAST HDL_TAP TRUE
J 0
(2675 1400);
DISPLAY 0.872340 (2675 1400);
DISPLAY INVISIBLE (2675 1400);
FORCEPROP 1 LAST PATH I115
J 0
(2348 1525);
DISPLAY 0.872340 (2348 1525);
PAINT GREEN (2348 1525);
DISPLAY INVISIBLE (2348 1525);
FORCEADD TAP..1
(2350 1575);
FORCEPROP 3 LASTPIN (2300 1575) SIG_NAME M_E_CPU1_SA_CA<4>
J 0
(2310 1585);
DISPLAY 0.659574 (2310 1585);
PAINT MONO (2310 1585);
DISPLAY INVISIBLE (2310 1585);
FORCEPROP 1 LASTPIN (2300 1575) BN 4
J 0
(2288 1583);
DISPLAY 0.680851 (2288 1583);
PAINT GREEN (2288 1583);
FORCEPROP 2 LAST CDS_LIB standard
J 0
(2350 1575);
DISPLAY INVISIBLE (2350 1575);
FORCEPROP 1 LAST BODY_TYPE PLUMBING
J 0
(2350 1625);
DISPLAY 0.872340 (2350 1625);
PAINT GREEN (2350 1625);
DISPLAY INVISIBLE (2350 1625);
FORCEPROP 1 LAST HDL_TAP TRUE
J 0
(2675 1450);
DISPLAY 0.872340 (2675 1450);
DISPLAY INVISIBLE (2675 1450);
FORCEPROP 1 LAST PATH I116
J 0
(2348 1575);
DISPLAY 0.872340 (2348 1575);
PAINT GREEN (2348 1575);
DISPLAY INVISIBLE (2348 1575);
FORCEADD TAP..1
(2350 1975);
FORCEPROP 3 LASTPIN (2300 1975) SIG_NAME M_E_CPU1_SB_DQS_DN<3>
J 0
(2310 1985);
DISPLAY 0.659574 (2310 1985);
PAINT MONO (2310 1985);
DISPLAY INVISIBLE (2310 1985);
FORCEPROP 1 LASTPIN (2300 1975) BN 3
J 0
(2288 1983);
DISPLAY 0.680851 (2288 1983);
PAINT GREEN (2288 1983);
FORCEPROP 2 LAST CDS_LIB standard
J 0
(2350 1975);
DISPLAY INVISIBLE (2350 1975);
FORCEPROP 1 LAST BODY_TYPE PLUMBING
J 0
(2350 2025);
DISPLAY 0.872340 (2350 2025);
PAINT GREEN (2350 2025);
DISPLAY INVISIBLE (2350 2025);
FORCEPROP 1 LAST HDL_TAP TRUE
J 0
(2675 1850);
DISPLAY 0.872340 (2675 1850);
DISPLAY INVISIBLE (2675 1850);
FORCEPROP 1 LAST PATH I117
J 0
(2348 1975);
DISPLAY 0.872340 (2348 1975);
PAINT GREEN (2348 1975);
DISPLAY INVISIBLE (2348 1975);
FORCEADD TAP..1
(2350 1875);
FORCEPROP 3 LASTPIN (2300 1875) SIG_NAME M_E_CPU1_SB_DQS_DN<1>
J 0
(2310 1885);
DISPLAY 0.659574 (2310 1885);
PAINT MONO (2310 1885);
DISPLAY INVISIBLE (2310 1885);
FORCEPROP 1 LASTPIN (2300 1875) BN 1
J 0
(2288 1883);
DISPLAY 0.680851 (2288 1883);
PAINT GREEN (2288 1883);
FORCEPROP 2 LAST CDS_LIB standard
J 0
(2350 1875);
DISPLAY INVISIBLE (2350 1875);
FORCEPROP 1 LAST BODY_TYPE PLUMBING
J 0
(2350 1925);
DISPLAY 0.872340 (2350 1925);
PAINT GREEN (2350 1925);
DISPLAY INVISIBLE (2350 1925);
FORCEPROP 1 LAST HDL_TAP TRUE
J 0
(2675 1750);
DISPLAY 0.872340 (2675 1750);
DISPLAY INVISIBLE (2675 1750);
FORCEPROP 1 LAST PATH I118
J 0
(2348 1875);
DISPLAY 0.872340 (2348 1875);
PAINT GREEN (2348 1875);
DISPLAY INVISIBLE (2348 1875);
FORCEADD TAP..1
(2350 1925);
FORCEPROP 3 LASTPIN (2300 1925) SIG_NAME M_E_CPU1_SB_DQS_DN<2>
J 0
(2310 1935);
DISPLAY 0.659574 (2310 1935);
PAINT MONO (2310 1935);
DISPLAY INVISIBLE (2310 1935);
FORCEPROP 1 LASTPIN (2300 1925) BN 2
J 0
(2288 1933);
DISPLAY 0.680851 (2288 1933);
PAINT GREEN (2288 1933);
FORCEPROP 2 LAST CDS_LIB standard
J 0
(2350 1925);
DISPLAY INVISIBLE (2350 1925);
FORCEPROP 1 LAST BODY_TYPE PLUMBING
J 0
(2350 1975);
DISPLAY 0.872340 (2350 1975);
PAINT GREEN (2350 1975);
DISPLAY INVISIBLE (2350 1975);
FORCEPROP 1 LAST HDL_TAP TRUE
J 0
(2675 1800);
DISPLAY 0.872340 (2675 1800);
DISPLAY INVISIBLE (2675 1800);
FORCEPROP 1 LAST PATH I119
J 0
(2348 1925);
DISPLAY 0.872340 (2348 1925);
PAINT GREEN (2348 1925);
DISPLAY INVISIBLE (2348 1925);
FORCEADD TAP..1
R 2
(-1075 125);
FORCEPROP 3 LASTPIN (-1025 125) SIG_NAME M_E_CPU1_SB_CB<2>
J 0
(-1015 135);
DISPLAY 0.659574 (-1015 135);
PAINT MONO (-1015 135);
DISPLAY INVISIBLE (-1015 135);
FORCEPROP 1 LASTPIN (-1025 125) BN 2
J 2
(-1013 133);
DISPLAY 0.680851 (-1013 133);
PAINT GREEN (-1013 133);
FORCEPROP 2 LAST CDS_LIB standard
J 0
(-1075 125);
DISPLAY INVISIBLE (-1075 125);
FORCEPROP 1 LAST BODY_TYPE PLUMBING
J 2
(-1075 175);
DISPLAY 0.872340 (-1075 175);
PAINT GREEN (-1075 175);
DISPLAY INVISIBLE (-1075 175);
FORCEPROP 1 LAST HDL_TAP TRUE
J 2
(-1400 0);
DISPLAY 0.872340 (-1400 0);
DISPLAY INVISIBLE (-1400 0);
FORCEPROP 1 LAST PATH I12
J 2
(-1073 125);
DISPLAY 0.872340 (-1073 125);
PAINT GREEN (-1073 125);
DISPLAY INVISIBLE (-1073 125);
FORCEADD TAP..1
(2350 1825);
FORCEPROP 3 LASTPIN (2300 1825) SIG_NAME M_E_CPU1_SB_DQS_DN<0>
J 0
(2310 1835);
DISPLAY 0.659574 (2310 1835);
PAINT MONO (2310 1835);
DISPLAY INVISIBLE (2310 1835);
FORCEPROP 1 LASTPIN (2300 1825) BN 0
J 0
(2288 1833);
DISPLAY 0.680851 (2288 1833);
PAINT GREEN (2288 1833);
FORCEPROP 2 LAST CDS_LIB standard
J 0
(2350 1825);
DISPLAY INVISIBLE (2350 1825);
FORCEPROP 1 LAST BODY_TYPE PLUMBING
J 0
(2350 1875);
DISPLAY 0.872340 (2350 1875);
PAINT GREEN (2350 1875);
DISPLAY INVISIBLE (2350 1875);
FORCEPROP 1 LAST HDL_TAP TRUE
J 0
(2675 1700);
DISPLAY 0.872340 (2675 1700);
DISPLAY INVISIBLE (2675 1700);
FORCEPROP 1 LAST PATH I120
J 0
(2348 1825);
DISPLAY 0.872340 (2348 1825);
PAINT GREEN (2348 1825);
DISPLAY INVISIBLE (2348 1825);
FORCEADD OFFPAGE..4
(3450 25);
FORCEPROP 2 LAST $XR0 106 
J 0
(3636 25);
DISPLAY 0.638298 (3636 25);
PAINT MONO (3636 25);
FORCEPROP 2 LAST CDS_LIB standard
J 0
(3450 25);
PAINT MONO (3450 25);
DISPLAY INVISIBLE (3450 25);
FORCEPROP 1 LAST OFFPAGE TRUE
J 0
(3775 -100);
DISPLAY 1.170213 (3775 -100);
PAINT GREEN (3775 -100);
DISPLAY INVISIBLE (3775 -100);
FORCEPROP 1 LAST COMMENT_BODY TRUE
J 0
(3425 -75);
DISPLAY 1.170213 (3425 -75);
PAINT GREEN (3425 -75);
DISPLAY INVISIBLE (3425 -75);
FORCEPROP 2 LAST PATH I121
J 0
(3625 100);
DISPLAY 1.021277 (3625 100);
DISPLAY INVISIBLE (3625 100);
FORCEADD OFFPAGE..4
(3450 75);
FORCEPROP 2 LAST $XR0 107 
J 0
(3636 75);
DISPLAY 0.638298 (3636 75);
PAINT MONO (3636 75);
FORCEPROP 2 LAST CDS_LIB standard
J 0
(3450 75);
PAINT MONO (3450 75);
DISPLAY INVISIBLE (3450 75);
FORCEPROP 1 LAST OFFPAGE TRUE
J 0
(3775 -50);
DISPLAY 1.170213 (3775 -50);
PAINT GREEN (3775 -50);
DISPLAY INVISIBLE (3775 -50);
FORCEPROP 1 LAST COMMENT_BODY TRUE
J 0
(3425 -25);
DISPLAY 1.170213 (3425 -25);
PAINT GREEN (3425 -25);
DISPLAY INVISIBLE (3425 -25);
FORCEPROP 2 LAST PATH I122
J 0
(3625 150);
DISPLAY 1.021277 (3625 150);
DISPLAY INVISIBLE (3625 150);
FORCEADD OFFPAGE..2
(3450 400);
FORCEPROP 2 LAST $XR1 107 
J 0
(3759 400);
DISPLAY 0.638298 (3759 400);
PAINT MONO (3759 400);
FORCEPROP 2 LAST $XR0 106 
J 0
(3639 400);
DISPLAY 0.638298 (3639 400);
PAINT MONO (3639 400);
FORCEPROP 2 LAST CDS_LIB standard
J 0
(3450 400);
PAINT MONO (3450 400);
DISPLAY INVISIBLE (3450 400);
FORCEPROP 1 LAST OFFPAGE TRUE
J 0
(3775 275);
DISPLAY 1.170213 (3775 275);
PAINT GREEN (3775 275);
DISPLAY INVISIBLE (3775 275);
FORCEPROP 1 LAST COMMENT_BODY TRUE
J 0
(3405 305);
DISPLAY 1.170213 (3405 305);
PAINT GREEN (3405 305);
DISPLAY INVISIBLE (3405 305);
FORCEPROP 2 LAST PATH I123
J 0
(3625 475);
DISPLAY 1.021277 (3625 475);
DISPLAY INVISIBLE (3625 475);
FORCEADD OFFPAGE..2
(3450 700);
FORCEPROP 2 LAST $XR1 107 
J 0
(3759 700);
DISPLAY 0.638298 (3759 700);
PAINT MONO (3759 700);
FORCEPROP 2 LAST $XR0 106 
J 0
(3639 700);
DISPLAY 0.638298 (3639 700);
PAINT MONO (3639 700);
FORCEPROP 2 LAST CDS_LIB standard
J 0
(3450 700);
PAINT MONO (3450 700);
DISPLAY INVISIBLE (3450 700);
FORCEPROP 1 LAST OFFPAGE TRUE
J 0
(3775 575);
DISPLAY 1.170213 (3775 575);
PAINT GREEN (3775 575);
DISPLAY INVISIBLE (3775 575);
FORCEPROP 1 LAST COMMENT_BODY TRUE
J 0
(3405 605);
DISPLAY 1.170213 (3405 605);
PAINT GREEN (3405 605);
DISPLAY INVISIBLE (3405 605);
FORCEPROP 2 LAST PATH I124
J 0
(3625 775);
DISPLAY 1.021277 (3625 775);
DISPLAY INVISIBLE (3625 775);
FORCEADD OFFPAGE..2
(3450 825);
FORCEPROP 2 LAST $XR1 107 
J 0
(3759 825);
DISPLAY 0.638298 (3759 825);
PAINT MONO (3759 825);
FORCEPROP 2 LAST $XR0 106 
J 0
(3639 825);
DISPLAY 0.638298 (3639 825);
PAINT MONO (3639 825);
FORCEPROP 2 LAST CDS_LIB standard
J 0
(3450 825);
PAINT MONO (3450 825);
DISPLAY INVISIBLE (3450 825);
FORCEPROP 1 LAST OFFPAGE TRUE
J 0
(3775 700);
DISPLAY 1.170213 (3775 700);
PAINT GREEN (3775 700);
DISPLAY INVISIBLE (3775 700);
FORCEPROP 1 LAST COMMENT_BODY TRUE
J 0
(3405 730);
DISPLAY 1.170213 (3405 730);
PAINT GREEN (3405 730);
DISPLAY INVISIBLE (3405 730);
FORCEPROP 2 LAST PATH I125
J 0
(3625 900);
DISPLAY 1.021277 (3625 900);
DISPLAY INVISIBLE (3625 900);
FORCEADD OFFPAGE..2
(3450 1325);
FORCEPROP 2 LAST $XR1 107 
J 0
(3759 1325);
DISPLAY 0.638298 (3759 1325);
PAINT MONO (3759 1325);
FORCEPROP 2 LAST $XR0 106 
J 0
(3639 1325);
DISPLAY 0.638298 (3639 1325);
PAINT MONO (3639 1325);
FORCEPROP 2 LAST CDS_LIB standard
J 0
(3450 1325);
PAINT MONO (3450 1325);
DISPLAY INVISIBLE (3450 1325);
FORCEPROP 1 LAST OFFPAGE TRUE
J 0
(3775 1200);
DISPLAY 1.170213 (3775 1200);
PAINT GREEN (3775 1200);
DISPLAY INVISIBLE (3775 1200);
FORCEPROP 1 LAST COMMENT_BODY TRUE
J 0
(3405 1230);
DISPLAY 1.170213 (3405 1230);
PAINT GREEN (3405 1230);
DISPLAY INVISIBLE (3405 1230);
FORCEPROP 2 LAST PATH I126
J 0
(3625 1400);
DISPLAY 1.021277 (3625 1400);
DISPLAY INVISIBLE (3625 1400);
FORCEADD OFFPAGE..3
(3450 1200);
FORCEPROP 2 LAST $XR1 107 
J 0
(3784 1200);
DISPLAY 0.638298 (3784 1200);
PAINT MONO (3784 1200);
FORCEPROP 2 LAST $XR0 106 
J 0
(3664 1200);
DISPLAY 0.638298 (3664 1200);
PAINT MONO (3664 1200);
FORCEPROP 2 LAST CDS_LIB standard
J 2
(3450 1200);
DISPLAY INVISIBLE (3450 1200);
FORCEPROP 1 LAST OFFPAGE TRUE
J 0
(3775 1075);
DISPLAY 0.872340 (3775 1075);
DISPLAY INVISIBLE (3775 1075);
FORCEPROP 1 LAST COMMENT_BODY TRUE
J 0
(3400 1100);
DISPLAY 0.872340 (3400 1100);
PAINT GREEN (3400 1100);
DISPLAY INVISIBLE (3400 1100);
FORCEPROP 2 LAST PATH I127
J 0
(3650 1275);
DISPLAY 1.021277 (3650 1275);
DISPLAY INVISIBLE (3650 1275);
FORCEADD OFFPAGE..3
(3450 1700);
FORCEPROP 2 LAST $XR1 107 
J 0
(3784 1700);
DISPLAY 0.638298 (3784 1700);
PAINT MONO (3784 1700);
FORCEPROP 2 LAST $XR0 106 
J 0
(3664 1700);
DISPLAY 0.638298 (3664 1700);
PAINT MONO (3664 1700);
FORCEPROP 2 LAST CDS_LIB standard
J 2
(3450 1700);
DISPLAY INVISIBLE (3450 1700);
FORCEPROP 1 LAST OFFPAGE TRUE
J 0
(3775 1575);
DISPLAY 0.872340 (3775 1575);
DISPLAY INVISIBLE (3775 1575);
FORCEPROP 1 LAST COMMENT_BODY TRUE
J 0
(3400 1600);
DISPLAY 0.872340 (3400 1600);
PAINT GREEN (3400 1600);
DISPLAY INVISIBLE (3400 1600);
FORCEPROP 2 LAST PATH I128
J 0
(3650 1775);
DISPLAY 1.021277 (3650 1775);
DISPLAY INVISIBLE (3650 1775);
FORCEADD TAP..1
(2350 2075);
FORCEPROP 3 LASTPIN (2300 2075) SIG_NAME M_E_CPU1_SB_DQS_DN<5>
J 0
(2310 2085);
DISPLAY 0.659574 (2310 2085);
PAINT MONO (2310 2085);
DISPLAY INVISIBLE (2310 2085);
FORCEPROP 1 LASTPIN (2300 2075) BN 5
J 0
(2288 2083);
DISPLAY 0.680851 (2288 2083);
PAINT GREEN (2288 2083);
FORCEPROP 2 LAST CDS_LIB standard
J 0
(2350 2075);
DISPLAY INVISIBLE (2350 2075);
FORCEPROP 1 LAST BODY_TYPE PLUMBING
J 0
(2350 2125);
DISPLAY 0.872340 (2350 2125);
PAINT GREEN (2350 2125);
DISPLAY INVISIBLE (2350 2125);
FORCEPROP 1 LAST HDL_TAP TRUE
J 0
(2675 1950);
DISPLAY 0.872340 (2675 1950);
DISPLAY INVISIBLE (2675 1950);
FORCEPROP 1 LAST PATH I129
J 0
(2348 2075);
DISPLAY 0.872340 (2348 2075);
PAINT GREEN (2348 2075);
DISPLAY INVISIBLE (2348 2075);
FORCEADD TAP..1
R 2
(-1075 175);
FORCEPROP 3 LASTPIN (-1025 175) SIG_NAME M_E_CPU1_SB_CB<3>
J 0
(-1015 185);
DISPLAY 0.659574 (-1015 185);
PAINT MONO (-1015 185);
DISPLAY INVISIBLE (-1015 185);
FORCEPROP 1 LASTPIN (-1025 175) BN 3
J 2
(-1013 183);
DISPLAY 0.680851 (-1013 183);
PAINT GREEN (-1013 183);
FORCEPROP 2 LAST CDS_LIB standard
J 0
(-1075 175);
DISPLAY INVISIBLE (-1075 175);
FORCEPROP 1 LAST BODY_TYPE PLUMBING
J 2
(-1075 225);
DISPLAY 0.872340 (-1075 225);
PAINT GREEN (-1075 225);
DISPLAY INVISIBLE (-1075 225);
FORCEPROP 1 LAST HDL_TAP TRUE
J 2
(-1400 50);
DISPLAY 0.872340 (-1400 50);
DISPLAY INVISIBLE (-1400 50);
FORCEPROP 1 LAST PATH I13
J 2
(-1073 175);
DISPLAY 0.872340 (-1073 175);
PAINT GREEN (-1073 175);
DISPLAY INVISIBLE (-1073 175);
FORCEADD TAP..1
(2350 2025);
FORCEPROP 3 LASTPIN (2300 2025) SIG_NAME M_E_CPU1_SB_DQS_DN<4>
J 0
(2310 2035);
DISPLAY 0.659574 (2310 2035);
PAINT MONO (2310 2035);
DISPLAY INVISIBLE (2310 2035);
FORCEPROP 1 LASTPIN (2300 2025) BN 4
J 0
(2288 2033);
DISPLAY 0.680851 (2288 2033);
PAINT GREEN (2288 2033);
FORCEPROP 2 LAST CDS_LIB standard
J 0
(2350 2025);
DISPLAY INVISIBLE (2350 2025);
FORCEPROP 1 LAST BODY_TYPE PLUMBING
J 0
(2350 2075);
DISPLAY 0.872340 (2350 2075);
PAINT GREEN (2350 2075);
DISPLAY INVISIBLE (2350 2075);
FORCEPROP 1 LAST HDL_TAP TRUE
J 0
(2675 1900);
DISPLAY 0.872340 (2675 1900);
DISPLAY INVISIBLE (2675 1900);
FORCEPROP 1 LAST PATH I130
J 0
(2348 2025);
DISPLAY 0.872340 (2348 2025);
PAINT GREEN (2348 2025);
DISPLAY INVISIBLE (2348 2025);
FORCEADD TAP..1
(2350 2125);
FORCEPROP 3 LASTPIN (2300 2125) SIG_NAME M_E_CPU1_SB_DQS_DN<6>
J 0
(2310 2135);
DISPLAY 0.659574 (2310 2135);
PAINT MONO (2310 2135);
DISPLAY INVISIBLE (2310 2135);
FORCEPROP 1 LASTPIN (2300 2125) BN 6
J 0
(2288 2133);
DISPLAY 0.680851 (2288 2133);
PAINT GREEN (2288 2133);
FORCEPROP 2 LAST CDS_LIB standard
J 0
(2350 2125);
DISPLAY INVISIBLE (2350 2125);
FORCEPROP 1 LAST BODY_TYPE PLUMBING
J 0
(2350 2175);
DISPLAY 0.872340 (2350 2175);
PAINT GREEN (2350 2175);
DISPLAY INVISIBLE (2350 2175);
FORCEPROP 1 LAST HDL_TAP TRUE
J 0
(2675 2000);
DISPLAY 0.872340 (2675 2000);
DISPLAY INVISIBLE (2675 2000);
FORCEPROP 1 LAST PATH I131
J 0
(2348 2125);
DISPLAY 0.872340 (2348 2125);
PAINT GREEN (2348 2125);
DISPLAY INVISIBLE (2348 2125);
FORCEADD TAP..1
(2350 2175);
FORCEPROP 3 LASTPIN (2300 2175) SIG_NAME M_E_CPU1_SB_DQS_DN<7>
J 0
(2310 2185);
DISPLAY 0.659574 (2310 2185);
PAINT MONO (2310 2185);
DISPLAY INVISIBLE (2310 2185);
FORCEPROP 1 LASTPIN (2300 2175) BN 7
J 0
(2288 2183);
DISPLAY 0.680851 (2288 2183);
PAINT GREEN (2288 2183);
FORCEPROP 2 LAST CDS_LIB standard
J 0
(2350 2175);
DISPLAY INVISIBLE (2350 2175);
FORCEPROP 1 LAST BODY_TYPE PLUMBING
J 0
(2350 2225);
DISPLAY 0.872340 (2350 2225);
PAINT GREEN (2350 2225);
DISPLAY INVISIBLE (2350 2225);
FORCEPROP 1 LAST HDL_TAP TRUE
J 0
(2675 2050);
DISPLAY 0.872340 (2675 2050);
DISPLAY INVISIBLE (2675 2050);
FORCEPROP 1 LAST PATH I132
J 0
(2348 2175);
DISPLAY 0.872340 (2348 2175);
PAINT GREEN (2348 2175);
DISPLAY INVISIBLE (2348 2175);
FORCEADD TAP..1
(2350 2275);
FORCEPROP 3 LASTPIN (2300 2275) SIG_NAME M_E_CPU1_SB_DQS_DN<9>
J 0
(2310 2285);
DISPLAY 0.659574 (2310 2285);
PAINT MONO (2310 2285);
DISPLAY INVISIBLE (2310 2285);
FORCEPROP 1 LASTPIN (2300 2275) BN 9
J 0
(2288 2283);
DISPLAY 0.680851 (2288 2283);
PAINT GREEN (2288 2283);
FORCEPROP 2 LAST CDS_LIB standard
J 0
(2350 2275);
DISPLAY INVISIBLE (2350 2275);
FORCEPROP 1 LAST BODY_TYPE PLUMBING
J 0
(2350 2325);
DISPLAY 0.872340 (2350 2325);
PAINT GREEN (2350 2325);
DISPLAY INVISIBLE (2350 2325);
FORCEPROP 1 LAST HDL_TAP TRUE
J 0
(2675 2150);
DISPLAY 0.872340 (2675 2150);
DISPLAY INVISIBLE (2675 2150);
FORCEPROP 1 LAST PATH I133
J 0
(2348 2275);
DISPLAY 0.872340 (2348 2275);
PAINT GREEN (2348 2275);
DISPLAY INVISIBLE (2348 2275);
FORCEADD TAP..1
(2350 2225);
FORCEPROP 3 LASTPIN (2300 2225) SIG_NAME M_E_CPU1_SB_DQS_DN<8>
J 0
(2310 2235);
DISPLAY 0.659574 (2310 2235);
PAINT MONO (2310 2235);
DISPLAY INVISIBLE (2310 2235);
FORCEPROP 1 LASTPIN (2300 2225) BN 8
J 0
(2288 2233);
DISPLAY 0.680851 (2288 2233);
PAINT GREEN (2288 2233);
FORCEPROP 2 LAST CDS_LIB standard
J 0
(2350 2225);
DISPLAY INVISIBLE (2350 2225);
FORCEPROP 1 LAST BODY_TYPE PLUMBING
J 0
(2350 2275);
DISPLAY 0.872340 (2350 2275);
PAINT GREEN (2350 2275);
DISPLAY INVISIBLE (2350 2275);
FORCEPROP 1 LAST HDL_TAP TRUE
J 0
(2675 2100);
DISPLAY 0.872340 (2675 2100);
DISPLAY INVISIBLE (2675 2100);
FORCEPROP 1 LAST PATH I134
J 0
(2348 2225);
DISPLAY 0.872340 (2348 2225);
PAINT GREEN (2348 2225);
DISPLAY INVISIBLE (2348 2225);
FORCEADD TAP..1
(2350 2425);
FORCEPROP 3 LASTPIN (2300 2425) SIG_NAME M_E_CPU1_SB_DQS_DP<1>
J 0
(2310 2435);
DISPLAY 0.659574 (2310 2435);
PAINT MONO (2310 2435);
DISPLAY INVISIBLE (2310 2435);
FORCEPROP 1 LASTPIN (2300 2425) BN 1
J 0
(2288 2433);
DISPLAY 0.680851 (2288 2433);
PAINT GREEN (2288 2433);
FORCEPROP 2 LAST CDS_LIB standard
J 0
(2350 2425);
DISPLAY INVISIBLE (2350 2425);
FORCEPROP 1 LAST BODY_TYPE PLUMBING
J 0
(2350 2475);
DISPLAY 0.872340 (2350 2475);
PAINT GREEN (2350 2475);
DISPLAY INVISIBLE (2350 2475);
FORCEPROP 1 LAST HDL_TAP TRUE
J 0
(2675 2300);
DISPLAY 0.872340 (2675 2300);
DISPLAY INVISIBLE (2675 2300);
FORCEPROP 1 LAST PATH I135
J 0
(2348 2425);
DISPLAY 0.872340 (2348 2425);
PAINT GREEN (2348 2425);
DISPLAY INVISIBLE (2348 2425);
FORCEADD TAP..1
(2350 2475);
FORCEPROP 3 LASTPIN (2300 2475) SIG_NAME M_E_CPU1_SB_DQS_DP<2>
J 0
(2310 2485);
DISPLAY 0.659574 (2310 2485);
PAINT MONO (2310 2485);
DISPLAY INVISIBLE (2310 2485);
FORCEPROP 1 LASTPIN (2300 2475) BN 2
J 0
(2288 2483);
DISPLAY 0.680851 (2288 2483);
PAINT GREEN (2288 2483);
FORCEPROP 2 LAST CDS_LIB standard
J 0
(2350 2475);
DISPLAY INVISIBLE (2350 2475);
FORCEPROP 1 LAST BODY_TYPE PLUMBING
J 0
(2350 2525);
DISPLAY 0.872340 (2350 2525);
PAINT GREEN (2350 2525);
DISPLAY INVISIBLE (2350 2525);
FORCEPROP 1 LAST HDL_TAP TRUE
J 0
(2675 2350);
DISPLAY 0.872340 (2675 2350);
DISPLAY INVISIBLE (2675 2350);
FORCEPROP 1 LAST PATH I136
J 0
(2348 2475);
DISPLAY 0.872340 (2348 2475);
PAINT GREEN (2348 2475);
DISPLAY INVISIBLE (2348 2475);
FORCEADD TAP..1
(2350 2525);
FORCEPROP 3 LASTPIN (2300 2525) SIG_NAME M_E_CPU1_SB_DQS_DP<3>
J 0
(2310 2535);
DISPLAY 0.659574 (2310 2535);
PAINT MONO (2310 2535);
DISPLAY INVISIBLE (2310 2535);
FORCEPROP 1 LASTPIN (2300 2525) BN 3
J 0
(2288 2533);
DISPLAY 0.680851 (2288 2533);
PAINT GREEN (2288 2533);
FORCEPROP 2 LAST CDS_LIB standard
J 0
(2350 2525);
DISPLAY INVISIBLE (2350 2525);
FORCEPROP 1 LAST BODY_TYPE PLUMBING
J 0
(2350 2575);
DISPLAY 0.872340 (2350 2575);
PAINT GREEN (2350 2575);
DISPLAY INVISIBLE (2350 2575);
FORCEPROP 1 LAST HDL_TAP TRUE
J 0
(2675 2400);
DISPLAY 0.872340 (2675 2400);
DISPLAY INVISIBLE (2675 2400);
FORCEPROP 1 LAST PATH I137
J 0
(2348 2525);
DISPLAY 0.872340 (2348 2525);
PAINT GREEN (2348 2525);
DISPLAY INVISIBLE (2348 2525);
FORCEADD TAP..1
(2350 2375);
FORCEPROP 3 LASTPIN (2300 2375) SIG_NAME M_E_CPU1_SB_DQS_DP<0>
J 0
(2310 2385);
DISPLAY 0.659574 (2310 2385);
PAINT MONO (2310 2385);
DISPLAY INVISIBLE (2310 2385);
FORCEPROP 1 LASTPIN (2300 2375) BN 0
J 0
(2288 2383);
DISPLAY 0.680851 (2288 2383);
PAINT GREEN (2288 2383);
FORCEPROP 2 LAST CDS_LIB standard
J 0
(2350 2375);
DISPLAY INVISIBLE (2350 2375);
FORCEPROP 1 LAST BODY_TYPE PLUMBING
J 0
(2350 2425);
DISPLAY 0.872340 (2350 2425);
PAINT GREEN (2350 2425);
DISPLAY INVISIBLE (2350 2425);
FORCEPROP 1 LAST HDL_TAP TRUE
J 0
(2675 2250);
DISPLAY 0.872340 (2675 2250);
DISPLAY INVISIBLE (2675 2250);
FORCEPROP 1 LAST PATH I138
J 0
(2348 2375);
DISPLAY 0.872340 (2348 2375);
PAINT GREEN (2348 2375);
DISPLAY INVISIBLE (2348 2375);
FORCEADD TAP..1
(2350 2675);
FORCEPROP 3 LASTPIN (2300 2675) SIG_NAME M_E_CPU1_SB_DQS_DP<6>
J 0
(2310 2685);
DISPLAY 0.659574 (2310 2685);
PAINT MONO (2310 2685);
DISPLAY INVISIBLE (2310 2685);
FORCEPROP 1 LASTPIN (2300 2675) BN 6
J 0
(2288 2683);
DISPLAY 0.680851 (2288 2683);
PAINT GREEN (2288 2683);
FORCEPROP 2 LAST CDS_LIB standard
J 0
(2350 2675);
DISPLAY INVISIBLE (2350 2675);
FORCEPROP 1 LAST BODY_TYPE PLUMBING
J 0
(2350 2725);
DISPLAY 0.872340 (2350 2725);
PAINT GREEN (2350 2725);
DISPLAY INVISIBLE (2350 2725);
FORCEPROP 1 LAST HDL_TAP TRUE
J 0
(2675 2550);
DISPLAY 0.872340 (2675 2550);
DISPLAY INVISIBLE (2675 2550);
FORCEPROP 1 LAST PATH I139
J 0
(2348 2675);
DISPLAY 0.872340 (2348 2675);
PAINT GREEN (2348 2675);
DISPLAY INVISIBLE (2348 2675);
FORCEADD TAP..1
R 2
(-1075 225);
FORCEPROP 3 LASTPIN (-1025 225) SIG_NAME M_E_CPU1_SB_CB<4>
J 0
(-1015 235);
DISPLAY 0.659574 (-1015 235);
PAINT MONO (-1015 235);
DISPLAY INVISIBLE (-1015 235);
FORCEPROP 1 LASTPIN (-1025 225) BN 4
J 2
(-1013 233);
DISPLAY 0.680851 (-1013 233);
PAINT GREEN (-1013 233);
FORCEPROP 2 LAST CDS_LIB standard
J 0
(-1075 225);
DISPLAY INVISIBLE (-1075 225);
FORCEPROP 1 LAST BODY_TYPE PLUMBING
J 2
(-1075 275);
DISPLAY 0.872340 (-1075 275);
PAINT GREEN (-1075 275);
DISPLAY INVISIBLE (-1075 275);
FORCEPROP 1 LAST HDL_TAP TRUE
J 2
(-1400 100);
DISPLAY 0.872340 (-1400 100);
DISPLAY INVISIBLE (-1400 100);
FORCEPROP 1 LAST PATH I14
J 2
(-1073 225);
DISPLAY 0.872340 (-1073 225);
PAINT GREEN (-1073 225);
DISPLAY INVISIBLE (-1073 225);
FORCEADD TAP..1
(2350 2725);
FORCEPROP 3 LASTPIN (2300 2725) SIG_NAME M_E_CPU1_SB_DQS_DP<7>
J 0
(2310 2735);
DISPLAY 0.659574 (2310 2735);
PAINT MONO (2310 2735);
DISPLAY INVISIBLE (2310 2735);
FORCEPROP 1 LASTPIN (2300 2725) BN 7
J 0
(2288 2733);
DISPLAY 0.680851 (2288 2733);
PAINT GREEN (2288 2733);
FORCEPROP 2 LAST CDS_LIB standard
J 0
(2350 2725);
DISPLAY INVISIBLE (2350 2725);
FORCEPROP 1 LAST BODY_TYPE PLUMBING
J 0
(2350 2775);
DISPLAY 0.872340 (2350 2775);
PAINT GREEN (2350 2775);
DISPLAY INVISIBLE (2350 2775);
FORCEPROP 1 LAST HDL_TAP TRUE
J 0
(2675 2600);
DISPLAY 0.872340 (2675 2600);
DISPLAY INVISIBLE (2675 2600);
FORCEPROP 1 LAST PATH I140
J 0
(2348 2725);
DISPLAY 0.872340 (2348 2725);
PAINT GREEN (2348 2725);
DISPLAY INVISIBLE (2348 2725);
FORCEADD TAP..1
(2350 2775);
FORCEPROP 3 LASTPIN (2300 2775) SIG_NAME M_E_CPU1_SB_DQS_DP<8>
J 0
(2310 2785);
DISPLAY 0.659574 (2310 2785);
PAINT MONO (2310 2785);
DISPLAY INVISIBLE (2310 2785);
FORCEPROP 1 LASTPIN (2300 2775) BN 8
J 0
(2288 2783);
DISPLAY 0.680851 (2288 2783);
PAINT GREEN (2288 2783);
FORCEPROP 2 LAST CDS_LIB standard
J 0
(2350 2775);
DISPLAY INVISIBLE (2350 2775);
FORCEPROP 1 LAST BODY_TYPE PLUMBING
J 0
(2350 2825);
DISPLAY 0.872340 (2350 2825);
PAINT GREEN (2350 2825);
DISPLAY INVISIBLE (2350 2825);
FORCEPROP 1 LAST HDL_TAP TRUE
J 0
(2675 2650);
DISPLAY 0.872340 (2675 2650);
DISPLAY INVISIBLE (2675 2650);
FORCEPROP 1 LAST PATH I141
J 0
(2348 2775);
DISPLAY 0.872340 (2348 2775);
PAINT GREEN (2348 2775);
DISPLAY INVISIBLE (2348 2775);
FORCEADD TAP..1
(2350 2625);
FORCEPROP 3 LASTPIN (2300 2625) SIG_NAME M_E_CPU1_SB_DQS_DP<5>
J 0
(2310 2635);
DISPLAY 0.659574 (2310 2635);
PAINT MONO (2310 2635);
DISPLAY INVISIBLE (2310 2635);
FORCEPROP 1 LASTPIN (2300 2625) BN 5
J 0
(2288 2633);
DISPLAY 0.680851 (2288 2633);
PAINT GREEN (2288 2633);
FORCEPROP 2 LAST CDS_LIB standard
J 0
(2350 2625);
DISPLAY INVISIBLE (2350 2625);
FORCEPROP 1 LAST BODY_TYPE PLUMBING
J 0
(2350 2675);
DISPLAY 0.872340 (2350 2675);
PAINT GREEN (2350 2675);
DISPLAY INVISIBLE (2350 2675);
FORCEPROP 1 LAST HDL_TAP TRUE
J 0
(2675 2500);
DISPLAY 0.872340 (2675 2500);
DISPLAY INVISIBLE (2675 2500);
FORCEPROP 1 LAST PATH I142
J 0
(2348 2625);
DISPLAY 0.872340 (2348 2625);
PAINT GREEN (2348 2625);
DISPLAY INVISIBLE (2348 2625);
FORCEADD TAP..1
(2350 2575);
FORCEPROP 3 LASTPIN (2300 2575) SIG_NAME M_E_CPU1_SB_DQS_DP<4>
J 0
(2310 2585);
DISPLAY 0.659574 (2310 2585);
PAINT MONO (2310 2585);
DISPLAY INVISIBLE (2310 2585);
FORCEPROP 1 LASTPIN (2300 2575) BN 4
J 0
(2288 2583);
DISPLAY 0.680851 (2288 2583);
PAINT GREEN (2288 2583);
FORCEPROP 2 LAST CDS_LIB standard
J 0
(2350 2575);
DISPLAY INVISIBLE (2350 2575);
FORCEPROP 1 LAST BODY_TYPE PLUMBING
J 0
(2350 2625);
DISPLAY 0.872340 (2350 2625);
PAINT GREEN (2350 2625);
DISPLAY INVISIBLE (2350 2625);
FORCEPROP 1 LAST HDL_TAP TRUE
J 0
(2675 2450);
DISPLAY 0.872340 (2675 2450);
DISPLAY INVISIBLE (2675 2450);
FORCEPROP 1 LAST PATH I143
J 0
(2348 2575);
DISPLAY 0.872340 (2348 2575);
PAINT GREEN (2348 2575);
DISPLAY INVISIBLE (2348 2575);
FORCEADD TAP..1
(2350 2825);
FORCEPROP 3 LASTPIN (2300 2825) SIG_NAME M_E_CPU1_SB_DQS_DP<9>
J 0
(2310 2835);
DISPLAY 0.659574 (2310 2835);
PAINT MONO (2310 2835);
DISPLAY INVISIBLE (2310 2835);
FORCEPROP 1 LASTPIN (2300 2825) BN 9
J 0
(2288 2833);
DISPLAY 0.680851 (2288 2833);
PAINT GREEN (2288 2833);
FORCEPROP 2 LAST CDS_LIB standard
J 0
(2350 2825);
DISPLAY INVISIBLE (2350 2825);
FORCEPROP 1 LAST BODY_TYPE PLUMBING
J 0
(2350 2875);
DISPLAY 0.872340 (2350 2875);
PAINT GREEN (2350 2875);
DISPLAY INVISIBLE (2350 2875);
FORCEPROP 1 LAST HDL_TAP TRUE
J 0
(2675 2700);
DISPLAY 0.872340 (2675 2700);
DISPLAY INVISIBLE (2675 2700);
FORCEPROP 1 LAST PATH I144
J 0
(2348 2825);
DISPLAY 0.872340 (2348 2825);
PAINT GREEN (2348 2825);
DISPLAY INVISIBLE (2348 2825);
FORCEADD TAP..1
(2350 2975);
FORCEPROP 3 LASTPIN (2300 2975) SIG_NAME M_E_CPU1_SA_DQS_DN<0>
J 0
(2310 2985);
DISPLAY 0.659574 (2310 2985);
PAINT MONO (2310 2985);
DISPLAY INVISIBLE (2310 2985);
FORCEPROP 1 LASTPIN (2300 2975) BN 0
J 0
(2288 2983);
DISPLAY 0.680851 (2288 2983);
PAINT GREEN (2288 2983);
FORCEPROP 2 LAST CDS_LIB standard
J 0
(2350 2975);
DISPLAY INVISIBLE (2350 2975);
FORCEPROP 1 LAST BODY_TYPE PLUMBING
J 0
(2350 3025);
DISPLAY 0.872340 (2350 3025);
PAINT GREEN (2350 3025);
DISPLAY INVISIBLE (2350 3025);
FORCEPROP 1 LAST HDL_TAP TRUE
J 0
(2675 2850);
DISPLAY 0.872340 (2675 2850);
DISPLAY INVISIBLE (2675 2850);
FORCEPROP 1 LAST PATH I145
J 0
(2348 2975);
DISPLAY 0.872340 (2348 2975);
PAINT GREEN (2348 2975);
DISPLAY INVISIBLE (2348 2975);
FORCEADD TAP..1
(2350 3025);
FORCEPROP 3 LASTPIN (2300 3025) SIG_NAME M_E_CPU1_SA_DQS_DN<1>
J 0
(2310 3035);
DISPLAY 0.659574 (2310 3035);
PAINT MONO (2310 3035);
DISPLAY INVISIBLE (2310 3035);
FORCEPROP 1 LASTPIN (2300 3025) BN 1
J 0
(2288 3033);
DISPLAY 0.680851 (2288 3033);
PAINT GREEN (2288 3033);
FORCEPROP 2 LAST CDS_LIB standard
J 0
(2350 3025);
DISPLAY INVISIBLE (2350 3025);
FORCEPROP 1 LAST BODY_TYPE PLUMBING
J 0
(2350 3075);
DISPLAY 0.872340 (2350 3075);
PAINT GREEN (2350 3075);
DISPLAY INVISIBLE (2350 3075);
FORCEPROP 1 LAST HDL_TAP TRUE
J 0
(2675 2900);
DISPLAY 0.872340 (2675 2900);
DISPLAY INVISIBLE (2675 2900);
FORCEPROP 1 LAST PATH I146
J 0
(2348 3025);
DISPLAY 0.872340 (2348 3025);
PAINT GREEN (2348 3025);
DISPLAY INVISIBLE (2348 3025);
FORCEADD TAP..1
(2350 3225);
FORCEPROP 3 LASTPIN (2300 3225) SIG_NAME M_E_CPU1_SA_DQS_DN<5>
J 0
(2310 3235);
DISPLAY 0.659574 (2310 3235);
PAINT MONO (2310 3235);
DISPLAY INVISIBLE (2310 3235);
FORCEPROP 1 LASTPIN (2300 3225) BN 5
J 0
(2288 3233);
DISPLAY 0.680851 (2288 3233);
PAINT GREEN (2288 3233);
FORCEPROP 2 LAST CDS_LIB standard
J 0
(2350 3225);
DISPLAY INVISIBLE (2350 3225);
FORCEPROP 1 LAST BODY_TYPE PLUMBING
J 0
(2350 3275);
DISPLAY 0.872340 (2350 3275);
PAINT GREEN (2350 3275);
DISPLAY INVISIBLE (2350 3275);
FORCEPROP 1 LAST HDL_TAP TRUE
J 0
(2675 3100);
DISPLAY 0.872340 (2675 3100);
DISPLAY INVISIBLE (2675 3100);
FORCEPROP 1 LAST PATH I147
J 0
(2348 3225);
DISPLAY 0.872340 (2348 3225);
PAINT GREEN (2348 3225);
DISPLAY INVISIBLE (2348 3225);
FORCEADD TAP..1
(2350 3275);
FORCEPROP 3 LASTPIN (2300 3275) SIG_NAME M_E_CPU1_SA_DQS_DN<6>
J 0
(2310 3285);
DISPLAY 0.659574 (2310 3285);
PAINT MONO (2310 3285);
DISPLAY INVISIBLE (2310 3285);
FORCEPROP 1 LASTPIN (2300 3275) BN 6
J 0
(2288 3283);
DISPLAY 0.680851 (2288 3283);
PAINT GREEN (2288 3283);
FORCEPROP 2 LAST CDS_LIB standard
J 0
(2350 3275);
DISPLAY INVISIBLE (2350 3275);
FORCEPROP 1 LAST BODY_TYPE PLUMBING
J 0
(2350 3325);
DISPLAY 0.872340 (2350 3325);
PAINT GREEN (2350 3325);
DISPLAY INVISIBLE (2350 3325);
FORCEPROP 1 LAST HDL_TAP TRUE
J 0
(2675 3150);
DISPLAY 0.872340 (2675 3150);
DISPLAY INVISIBLE (2675 3150);
FORCEPROP 1 LAST PATH I148
J 0
(2348 3275);
DISPLAY 0.872340 (2348 3275);
PAINT GREEN (2348 3275);
DISPLAY INVISIBLE (2348 3275);
FORCEADD TAP..1
(2350 3175);
FORCEPROP 3 LASTPIN (2300 3175) SIG_NAME M_E_CPU1_SA_DQS_DN<4>
J 0
(2310 3185);
DISPLAY 0.659574 (2310 3185);
PAINT MONO (2310 3185);
DISPLAY INVISIBLE (2310 3185);
FORCEPROP 1 LASTPIN (2300 3175) BN 4
J 0
(2288 3183);
DISPLAY 0.680851 (2288 3183);
PAINT GREEN (2288 3183);
FORCEPROP 2 LAST CDS_LIB standard
J 0
(2350 3175);
DISPLAY INVISIBLE (2350 3175);
FORCEPROP 1 LAST BODY_TYPE PLUMBING
J 0
(2350 3225);
DISPLAY 0.872340 (2350 3225);
PAINT GREEN (2350 3225);
DISPLAY INVISIBLE (2350 3225);
FORCEPROP 1 LAST HDL_TAP TRUE
J 0
(2675 3050);
DISPLAY 0.872340 (2675 3050);
DISPLAY INVISIBLE (2675 3050);
FORCEPROP 1 LAST PATH I149
J 0
(2348 3175);
DISPLAY 0.872340 (2348 3175);
PAINT GREEN (2348 3175);
DISPLAY INVISIBLE (2348 3175);
FORCEADD TAP..1
R 2
(-1075 275);
FORCEPROP 3 LASTPIN (-1025 275) SIG_NAME M_E_CPU1_SB_CB<5>
J 0
(-1015 285);
DISPLAY 0.659574 (-1015 285);
PAINT MONO (-1015 285);
DISPLAY INVISIBLE (-1015 285);
FORCEPROP 1 LASTPIN (-1025 275) BN 5
J 2
(-1013 283);
DISPLAY 0.680851 (-1013 283);
PAINT GREEN (-1013 283);
FORCEPROP 2 LAST CDS_LIB standard
J 0
(-1075 275);
DISPLAY INVISIBLE (-1075 275);
FORCEPROP 1 LAST BODY_TYPE PLUMBING
J 2
(-1075 325);
DISPLAY 0.872340 (-1075 325);
PAINT GREEN (-1075 325);
DISPLAY INVISIBLE (-1075 325);
FORCEPROP 1 LAST HDL_TAP TRUE
J 2
(-1400 150);
DISPLAY 0.872340 (-1400 150);
DISPLAY INVISIBLE (-1400 150);
FORCEPROP 1 LAST PATH I15
J 2
(-1073 275);
DISPLAY 0.872340 (-1073 275);
PAINT GREEN (-1073 275);
DISPLAY INVISIBLE (-1073 275);
FORCEADD TAP..1
(2350 3125);
FORCEPROP 3 LASTPIN (2300 3125) SIG_NAME M_E_CPU1_SA_DQS_DN<3>
J 0
(2310 3135);
DISPLAY 0.659574 (2310 3135);
PAINT MONO (2310 3135);
DISPLAY INVISIBLE (2310 3135);
FORCEPROP 1 LASTPIN (2300 3125) BN 3
J 0
(2288 3133);
DISPLAY 0.680851 (2288 3133);
PAINT GREEN (2288 3133);
FORCEPROP 2 LAST CDS_LIB standard
J 0
(2350 3125);
DISPLAY INVISIBLE (2350 3125);
FORCEPROP 1 LAST BODY_TYPE PLUMBING
J 0
(2350 3175);
DISPLAY 0.872340 (2350 3175);
PAINT GREEN (2350 3175);
DISPLAY INVISIBLE (2350 3175);
FORCEPROP 1 LAST HDL_TAP TRUE
J 0
(2675 3000);
DISPLAY 0.872340 (2675 3000);
DISPLAY INVISIBLE (2675 3000);
FORCEPROP 1 LAST PATH I150
J 0
(2348 3125);
DISPLAY 0.872340 (2348 3125);
PAINT GREEN (2348 3125);
DISPLAY INVISIBLE (2348 3125);
FORCEADD TAP..1
(2350 3075);
FORCEPROP 3 LASTPIN (2300 3075) SIG_NAME M_E_CPU1_SA_DQS_DN<2>
J 0
(2310 3085);
DISPLAY 0.659574 (2310 3085);
PAINT MONO (2310 3085);
DISPLAY INVISIBLE (2310 3085);
FORCEPROP 1 LASTPIN (2300 3075) BN 2
J 0
(2288 3083);
DISPLAY 0.680851 (2288 3083);
PAINT GREEN (2288 3083);
FORCEPROP 2 LAST CDS_LIB standard
J 0
(2350 3075);
DISPLAY INVISIBLE (2350 3075);
FORCEPROP 1 LAST BODY_TYPE PLUMBING
J 0
(2350 3125);
DISPLAY 0.872340 (2350 3125);
PAINT GREEN (2350 3125);
DISPLAY INVISIBLE (2350 3125);
FORCEPROP 1 LAST HDL_TAP TRUE
J 0
(2675 2950);
DISPLAY 0.872340 (2675 2950);
DISPLAY INVISIBLE (2675 2950);
FORCEPROP 1 LAST PATH I151
J 0
(2348 3075);
DISPLAY 0.872340 (2348 3075);
PAINT GREEN (2348 3075);
DISPLAY INVISIBLE (2348 3075);
FORCEADD TAP..1
(2350 3325);
FORCEPROP 3 LASTPIN (2300 3325) SIG_NAME M_E_CPU1_SA_DQS_DN<7>
J 0
(2310 3335);
DISPLAY 0.659574 (2310 3335);
PAINT MONO (2310 3335);
DISPLAY INVISIBLE (2310 3335);
FORCEPROP 1 LASTPIN (2300 3325) BN 7
J 0
(2288 3333);
DISPLAY 0.680851 (2288 3333);
PAINT GREEN (2288 3333);
FORCEPROP 2 LAST CDS_LIB standard
J 0
(2350 3325);
DISPLAY INVISIBLE (2350 3325);
FORCEPROP 1 LAST BODY_TYPE PLUMBING
J 0
(2350 3375);
DISPLAY 0.872340 (2350 3375);
PAINT GREEN (2350 3375);
DISPLAY INVISIBLE (2350 3375);
FORCEPROP 1 LAST HDL_TAP TRUE
J 0
(2675 3200);
DISPLAY 0.872340 (2675 3200);
DISPLAY INVISIBLE (2675 3200);
FORCEPROP 1 LAST PATH I152
J 0
(2348 3325);
DISPLAY 0.872340 (2348 3325);
PAINT GREEN (2348 3325);
DISPLAY INVISIBLE (2348 3325);
FORCEADD TAP..1
(2350 3525);
FORCEPROP 3 LASTPIN (2300 3525) SIG_NAME M_E_CPU1_SA_DQS_DP<0>
J 0
(2310 3535);
DISPLAY 0.659574 (2310 3535);
PAINT MONO (2310 3535);
DISPLAY INVISIBLE (2310 3535);
FORCEPROP 1 LASTPIN (2300 3525) BN 0
J 0
(2288 3533);
DISPLAY 0.680851 (2288 3533);
PAINT GREEN (2288 3533);
FORCEPROP 2 LAST CDS_LIB standard
J 0
(2350 3525);
DISPLAY INVISIBLE (2350 3525);
FORCEPROP 1 LAST BODY_TYPE PLUMBING
J 0
(2350 3575);
DISPLAY 0.872340 (2350 3575);
PAINT GREEN (2350 3575);
DISPLAY INVISIBLE (2350 3575);
FORCEPROP 1 LAST HDL_TAP TRUE
J 0
(2675 3400);
DISPLAY 0.872340 (2675 3400);
DISPLAY INVISIBLE (2675 3400);
FORCEPROP 1 LAST PATH I153
J 0
(2348 3525);
DISPLAY 0.872340 (2348 3525);
PAINT GREEN (2348 3525);
DISPLAY INVISIBLE (2348 3525);
FORCEADD TAP..1
(2350 3425);
FORCEPROP 3 LASTPIN (2300 3425) SIG_NAME M_E_CPU1_SA_DQS_DN<9>
J 0
(2310 3435);
DISPLAY 0.659574 (2310 3435);
PAINT MONO (2310 3435);
DISPLAY INVISIBLE (2310 3435);
FORCEPROP 1 LASTPIN (2300 3425) BN 9
J 0
(2288 3433);
DISPLAY 0.680851 (2288 3433);
PAINT GREEN (2288 3433);
FORCEPROP 2 LAST CDS_LIB standard
J 0
(2350 3425);
DISPLAY INVISIBLE (2350 3425);
FORCEPROP 1 LAST BODY_TYPE PLUMBING
J 0
(2350 3475);
DISPLAY 0.872340 (2350 3475);
PAINT GREEN (2350 3475);
DISPLAY INVISIBLE (2350 3475);
FORCEPROP 1 LAST HDL_TAP TRUE
J 0
(2675 3300);
DISPLAY 0.872340 (2675 3300);
DISPLAY INVISIBLE (2675 3300);
FORCEPROP 1 LAST PATH I154
J 0
(2348 3425);
DISPLAY 0.872340 (2348 3425);
PAINT GREEN (2348 3425);
DISPLAY INVISIBLE (2348 3425);
FORCEADD TAP..1
(2350 3375);
FORCEPROP 3 LASTPIN (2300 3375) SIG_NAME M_E_CPU1_SA_DQS_DN<8>
J 0
(2310 3385);
DISPLAY 0.659574 (2310 3385);
PAINT MONO (2310 3385);
DISPLAY INVISIBLE (2310 3385);
FORCEPROP 1 LASTPIN (2300 3375) BN 8
J 0
(2288 3383);
DISPLAY 0.680851 (2288 3383);
PAINT GREEN (2288 3383);
FORCEPROP 2 LAST CDS_LIB standard
J 0
(2350 3375);
DISPLAY INVISIBLE (2350 3375);
FORCEPROP 1 LAST BODY_TYPE PLUMBING
J 0
(2350 3425);
DISPLAY 0.872340 (2350 3425);
PAINT GREEN (2350 3425);
DISPLAY INVISIBLE (2350 3425);
FORCEPROP 1 LAST HDL_TAP TRUE
J 0
(2675 3250);
DISPLAY 0.872340 (2675 3250);
DISPLAY INVISIBLE (2675 3250);
FORCEPROP 1 LAST PATH I155
J 0
(2348 3375);
DISPLAY 0.872340 (2348 3375);
PAINT GREEN (2348 3375);
DISPLAY INVISIBLE (2348 3375);
FORCEADD TAP..1
(2350 3775);
FORCEPROP 3 LASTPIN (2300 3775) SIG_NAME M_E_CPU1_SA_DQS_DP<5>
J 0
(2310 3785);
DISPLAY 0.659574 (2310 3785);
PAINT MONO (2310 3785);
DISPLAY INVISIBLE (2310 3785);
FORCEPROP 1 LASTPIN (2300 3775) BN 5
J 0
(2288 3783);
DISPLAY 0.680851 (2288 3783);
PAINT GREEN (2288 3783);
FORCEPROP 2 LAST CDS_LIB standard
J 0
(2350 3775);
DISPLAY INVISIBLE (2350 3775);
FORCEPROP 1 LAST BODY_TYPE PLUMBING
J 0
(2350 3825);
DISPLAY 0.872340 (2350 3825);
PAINT GREEN (2350 3825);
DISPLAY INVISIBLE (2350 3825);
FORCEPROP 1 LAST HDL_TAP TRUE
J 0
(2675 3650);
DISPLAY 0.872340 (2675 3650);
DISPLAY INVISIBLE (2675 3650);
FORCEPROP 1 LAST PATH I156
J 0
(2348 3775);
DISPLAY 0.872340 (2348 3775);
PAINT GREEN (2348 3775);
DISPLAY INVISIBLE (2348 3775);
FORCEADD TAP..1
(2350 3675);
FORCEPROP 3 LASTPIN (2300 3675) SIG_NAME M_E_CPU1_SA_DQS_DP<3>
J 0
(2310 3685);
DISPLAY 0.659574 (2310 3685);
PAINT MONO (2310 3685);
DISPLAY INVISIBLE (2310 3685);
FORCEPROP 1 LASTPIN (2300 3675) BN 3
J 0
(2288 3683);
DISPLAY 0.680851 (2288 3683);
PAINT GREEN (2288 3683);
FORCEPROP 2 LAST CDS_LIB standard
J 0
(2350 3675);
DISPLAY INVISIBLE (2350 3675);
FORCEPROP 1 LAST BODY_TYPE PLUMBING
J 0
(2350 3725);
DISPLAY 0.872340 (2350 3725);
PAINT GREEN (2350 3725);
DISPLAY INVISIBLE (2350 3725);
FORCEPROP 1 LAST HDL_TAP TRUE
J 0
(2675 3550);
DISPLAY 0.872340 (2675 3550);
DISPLAY INVISIBLE (2675 3550);
FORCEPROP 1 LAST PATH I157
J 0
(2348 3675);
DISPLAY 0.872340 (2348 3675);
PAINT GREEN (2348 3675);
DISPLAY INVISIBLE (2348 3675);
FORCEADD TAP..1
(2350 3725);
FORCEPROP 3 LASTPIN (2300 3725) SIG_NAME M_E_CPU1_SA_DQS_DP<4>
J 0
(2310 3735);
DISPLAY 0.659574 (2310 3735);
PAINT MONO (2310 3735);
DISPLAY INVISIBLE (2310 3735);
FORCEPROP 1 LASTPIN (2300 3725) BN 4
J 0
(2288 3733);
DISPLAY 0.680851 (2288 3733);
PAINT GREEN (2288 3733);
FORCEPROP 2 LAST CDS_LIB standard
J 0
(2350 3725);
DISPLAY INVISIBLE (2350 3725);
FORCEPROP 1 LAST BODY_TYPE PLUMBING
J 0
(2350 3775);
DISPLAY 0.872340 (2350 3775);
PAINT GREEN (2350 3775);
DISPLAY INVISIBLE (2350 3775);
FORCEPROP 1 LAST HDL_TAP TRUE
J 0
(2675 3600);
DISPLAY 0.872340 (2675 3600);
DISPLAY INVISIBLE (2675 3600);
FORCEPROP 1 LAST PATH I158
J 0
(2348 3725);
DISPLAY 0.872340 (2348 3725);
PAINT GREEN (2348 3725);
DISPLAY INVISIBLE (2348 3725);
FORCEADD TAP..1
(2350 3575);
FORCEPROP 3 LASTPIN (2300 3575) SIG_NAME M_E_CPU1_SA_DQS_DP<1>
J 0
(2310 3585);
DISPLAY 0.659574 (2310 3585);
PAINT MONO (2310 3585);
DISPLAY INVISIBLE (2310 3585);
FORCEPROP 1 LASTPIN (2300 3575) BN 1
J 0
(2288 3583);
DISPLAY 0.680851 (2288 3583);
PAINT GREEN (2288 3583);
FORCEPROP 2 LAST CDS_LIB standard
J 0
(2350 3575);
DISPLAY INVISIBLE (2350 3575);
FORCEPROP 1 LAST BODY_TYPE PLUMBING
J 0
(2350 3625);
DISPLAY 0.872340 (2350 3625);
PAINT GREEN (2350 3625);
DISPLAY INVISIBLE (2350 3625);
FORCEPROP 1 LAST HDL_TAP TRUE
J 0
(2675 3450);
DISPLAY 0.872340 (2675 3450);
DISPLAY INVISIBLE (2675 3450);
FORCEPROP 1 LAST PATH I159
J 0
(2348 3575);
DISPLAY 0.872340 (2348 3575);
PAINT GREEN (2348 3575);
DISPLAY INVISIBLE (2348 3575);
FORCEADD TAP..1
R 2
(-1075 325);
FORCEPROP 3 LASTPIN (-1025 325) SIG_NAME M_E_CPU1_SB_CB<6>
J 0
(-1015 335);
DISPLAY 0.659574 (-1015 335);
PAINT MONO (-1015 335);
DISPLAY INVISIBLE (-1015 335);
FORCEPROP 1 LASTPIN (-1025 325) BN 6
J 2
(-1013 333);
DISPLAY 0.680851 (-1013 333);
PAINT GREEN (-1013 333);
FORCEPROP 2 LAST CDS_LIB standard
J 0
(-1075 325);
DISPLAY INVISIBLE (-1075 325);
FORCEPROP 1 LAST BODY_TYPE PLUMBING
J 2
(-1075 375);
DISPLAY 0.872340 (-1075 375);
PAINT GREEN (-1075 375);
DISPLAY INVISIBLE (-1075 375);
FORCEPROP 1 LAST HDL_TAP TRUE
J 2
(-1400 200);
DISPLAY 0.872340 (-1400 200);
DISPLAY INVISIBLE (-1400 200);
FORCEPROP 1 LAST PATH I16
J 2
(-1073 325);
DISPLAY 0.872340 (-1073 325);
PAINT GREEN (-1073 325);
DISPLAY INVISIBLE (-1073 325);
FORCEADD TAP..1
(2350 3625);
FORCEPROP 3 LASTPIN (2300 3625) SIG_NAME M_E_CPU1_SA_DQS_DP<2>
J 0
(2310 3635);
DISPLAY 0.659574 (2310 3635);
PAINT MONO (2310 3635);
DISPLAY INVISIBLE (2310 3635);
FORCEPROP 1 LASTPIN (2300 3625) BN 2
J 0
(2288 3633);
DISPLAY 0.680851 (2288 3633);
PAINT GREEN (2288 3633);
FORCEPROP 2 LAST CDS_LIB standard
J 0
(2350 3625);
DISPLAY INVISIBLE (2350 3625);
FORCEPROP 1 LAST BODY_TYPE PLUMBING
J 0
(2350 3675);
DISPLAY 0.872340 (2350 3675);
PAINT GREEN (2350 3675);
DISPLAY INVISIBLE (2350 3675);
FORCEPROP 1 LAST HDL_TAP TRUE
J 0
(2675 3500);
DISPLAY 0.872340 (2675 3500);
DISPLAY INVISIBLE (2675 3500);
FORCEPROP 1 LAST PATH I160
J 0
(2348 3625);
DISPLAY 0.872340 (2348 3625);
PAINT GREEN (2348 3625);
DISPLAY INVISIBLE (2348 3625);
FORCEADD TAP..1
(2350 3975);
FORCEPROP 3 LASTPIN (2300 3975) SIG_NAME M_E_CPU1_SA_DQS_DP<9>
J 0
(2310 3985);
DISPLAY 0.659574 (2310 3985);
PAINT MONO (2310 3985);
DISPLAY INVISIBLE (2310 3985);
FORCEPROP 1 LASTPIN (2300 3975) BN 9
J 0
(2288 3983);
DISPLAY 0.680851 (2288 3983);
PAINT GREEN (2288 3983);
FORCEPROP 2 LAST CDS_LIB standard
J 0
(2350 3975);
DISPLAY INVISIBLE (2350 3975);
FORCEPROP 1 LAST BODY_TYPE PLUMBING
J 0
(2350 4025);
DISPLAY 0.872340 (2350 4025);
PAINT GREEN (2350 4025);
DISPLAY INVISIBLE (2350 4025);
FORCEPROP 1 LAST HDL_TAP TRUE
J 0
(2675 3850);
DISPLAY 0.872340 (2675 3850);
DISPLAY INVISIBLE (2675 3850);
FORCEPROP 1 LAST PATH I161
J 0
(2348 3975);
DISPLAY 0.872340 (2348 3975);
PAINT GREEN (2348 3975);
DISPLAY INVISIBLE (2348 3975);
FORCEADD TAP..1
(2350 3925);
FORCEPROP 3 LASTPIN (2300 3925) SIG_NAME M_E_CPU1_SA_DQS_DP<8>
J 0
(2310 3935);
DISPLAY 0.659574 (2310 3935);
PAINT MONO (2310 3935);
DISPLAY INVISIBLE (2310 3935);
FORCEPROP 1 LASTPIN (2300 3925) BN 8
J 0
(2288 3933);
DISPLAY 0.680851 (2288 3933);
PAINT GREEN (2288 3933);
FORCEPROP 2 LAST CDS_LIB standard
J 0
(2350 3925);
DISPLAY INVISIBLE (2350 3925);
FORCEPROP 1 LAST BODY_TYPE PLUMBING
J 0
(2350 3975);
DISPLAY 0.872340 (2350 3975);
PAINT GREEN (2350 3975);
DISPLAY INVISIBLE (2350 3975);
FORCEPROP 1 LAST HDL_TAP TRUE
J 0
(2675 3800);
DISPLAY 0.872340 (2675 3800);
DISPLAY INVISIBLE (2675 3800);
FORCEPROP 1 LAST PATH I162
J 0
(2348 3925);
DISPLAY 0.872340 (2348 3925);
PAINT GREEN (2348 3925);
DISPLAY INVISIBLE (2348 3925);
FORCEADD TAP..1
(2350 3825);
FORCEPROP 3 LASTPIN (2300 3825) SIG_NAME M_E_CPU1_SA_DQS_DP<6>
J 0
(2310 3835);
DISPLAY 0.659574 (2310 3835);
PAINT MONO (2310 3835);
DISPLAY INVISIBLE (2310 3835);
FORCEPROP 1 LASTPIN (2300 3825) BN 6
J 0
(2288 3833);
DISPLAY 0.680851 (2288 3833);
PAINT GREEN (2288 3833);
FORCEPROP 2 LAST CDS_LIB standard
J 0
(2350 3825);
DISPLAY INVISIBLE (2350 3825);
FORCEPROP 1 LAST BODY_TYPE PLUMBING
J 0
(2350 3875);
DISPLAY 0.872340 (2350 3875);
PAINT GREEN (2350 3875);
DISPLAY INVISIBLE (2350 3875);
FORCEPROP 1 LAST HDL_TAP TRUE
J 0
(2675 3700);
DISPLAY 0.872340 (2675 3700);
DISPLAY INVISIBLE (2675 3700);
FORCEPROP 1 LAST PATH I163
J 0
(2348 3825);
DISPLAY 0.872340 (2348 3825);
PAINT GREEN (2348 3825);
DISPLAY INVISIBLE (2348 3825);
FORCEADD TAP..1
(2350 3875);
FORCEPROP 3 LASTPIN (2300 3875) SIG_NAME M_E_CPU1_SA_DQS_DP<7>
J 0
(2310 3885);
DISPLAY 0.659574 (2310 3885);
PAINT MONO (2310 3885);
DISPLAY INVISIBLE (2310 3885);
FORCEPROP 1 LASTPIN (2300 3875) BN 7
J 0
(2288 3883);
DISPLAY 0.680851 (2288 3883);
PAINT GREEN (2288 3883);
FORCEPROP 2 LAST CDS_LIB standard
J 0
(2350 3875);
DISPLAY INVISIBLE (2350 3875);
FORCEPROP 1 LAST BODY_TYPE PLUMBING
J 0
(2350 3925);
DISPLAY 0.872340 (2350 3925);
PAINT GREEN (2350 3925);
DISPLAY INVISIBLE (2350 3925);
FORCEPROP 1 LAST HDL_TAP TRUE
J 0
(2675 3750);
DISPLAY 0.872340 (2675 3750);
DISPLAY INVISIBLE (2675 3750);
FORCEPROP 1 LAST PATH I164
J 0
(2348 3875);
DISPLAY 0.872340 (2348 3875);
PAINT GREEN (2348 3875);
DISPLAY INVISIBLE (2348 3875);
FORCEADD OFFPAGE..3
(3450 2300);
FORCEPROP 2 LAST $XR1 107 
J 0
(3784 2300);
DISPLAY 0.638298 (3784 2300);
PAINT MONO (3784 2300);
FORCEPROP 2 LAST $XR0 106 
J 0
(3664 2300);
DISPLAY 0.638298 (3664 2300);
PAINT MONO (3664 2300);
FORCEPROP 2 LAST CDS_LIB standard
J 2
(3450 2300);
DISPLAY INVISIBLE (3450 2300);
FORCEPROP 1 LAST OFFPAGE TRUE
J 0
(3775 2175);
DISPLAY 0.872340 (3775 2175);
DISPLAY INVISIBLE (3775 2175);
FORCEPROP 1 LAST COMMENT_BODY TRUE
J 0
(3400 2200);
DISPLAY 0.872340 (3400 2200);
PAINT GREEN (3400 2200);
DISPLAY INVISIBLE (3400 2200);
FORCEPROP 2 LAST PATH I165
J 0
(3650 2375);
DISPLAY 1.021277 (3650 2375);
DISPLAY INVISIBLE (3650 2375);
FORCEADD OFFPAGE..3
(3450 2850);
FORCEPROP 2 LAST $XR1 107 
J 0
(3784 2850);
DISPLAY 0.638298 (3784 2850);
PAINT MONO (3784 2850);
FORCEPROP 2 LAST $XR0 106 
J 0
(3664 2850);
DISPLAY 0.638298 (3664 2850);
PAINT MONO (3664 2850);
FORCEPROP 2 LAST CDS_LIB standard
J 2
(3450 2850);
DISPLAY INVISIBLE (3450 2850);
FORCEPROP 1 LAST OFFPAGE TRUE
J 0
(3775 2725);
DISPLAY 0.872340 (3775 2725);
DISPLAY INVISIBLE (3775 2725);
FORCEPROP 1 LAST COMMENT_BODY TRUE
J 0
(3400 2750);
DISPLAY 0.872340 (3400 2750);
PAINT GREEN (3400 2750);
DISPLAY INVISIBLE (3400 2750);
FORCEPROP 2 LAST PATH I166
J 0
(3650 2925);
DISPLAY 1.021277 (3650 2925);
DISPLAY INVISIBLE (3650 2925);
FORCEADD OFFPAGE..3
(3450 3450);
FORCEPROP 2 LAST $XR1 107 
J 0
(3784 3450);
DISPLAY 0.638298 (3784 3450);
PAINT MONO (3784 3450);
FORCEPROP 2 LAST $XR0 106 
J 0
(3664 3450);
DISPLAY 0.638298 (3664 3450);
PAINT MONO (3664 3450);
FORCEPROP 2 LAST CDS_LIB standard
J 2
(3450 3450);
DISPLAY INVISIBLE (3450 3450);
FORCEPROP 1 LAST OFFPAGE TRUE
J 0
(3775 3325);
DISPLAY 0.872340 (3775 3325);
DISPLAY INVISIBLE (3775 3325);
FORCEPROP 1 LAST COMMENT_BODY TRUE
J 0
(3400 3350);
DISPLAY 0.872340 (3400 3350);
PAINT GREEN (3400 3350);
DISPLAY INVISIBLE (3400 3350);
FORCEPROP 2 LAST PATH I167
J 0
(3650 3525);
DISPLAY 1.021277 (3650 3525);
DISPLAY INVISIBLE (3650 3525);
FORCEADD OFFPAGE..3
(3450 4000);
FORCEPROP 2 LAST $XR1 107 
J 0
(3784 4000);
DISPLAY 0.638298 (3784 4000);
PAINT MONO (3784 4000);
FORCEPROP 2 LAST $XR0 106 
J 0
(3664 4000);
DISPLAY 0.638298 (3664 4000);
PAINT MONO (3664 4000);
FORCEPROP 2 LAST CDS_LIB standard
J 2
(3450 4000);
DISPLAY INVISIBLE (3450 4000);
FORCEPROP 1 LAST OFFPAGE TRUE
J 0
(3775 3875);
DISPLAY 0.872340 (3775 3875);
DISPLAY INVISIBLE (3775 3875);
FORCEPROP 1 LAST COMMENT_BODY TRUE
J 0
(3400 3900);
DISPLAY 0.872340 (3400 3900);
PAINT GREEN (3400 3900);
DISPLAY INVISIBLE (3400 3900);
FORCEPROP 2 LAST PATH I168
J 0
(3650 4075);
DISPLAY 1.021277 (3650 4075);
DISPLAY INVISIBLE (3650 4075);
FORCEADD TAP..1
R 2
(-1075 375);
FORCEPROP 3 LASTPIN (-1025 375) SIG_NAME M_E_CPU1_SB_CB<7>
J 0
(-1015 385);
DISPLAY 0.659574 (-1015 385);
PAINT MONO (-1015 385);
DISPLAY INVISIBLE (-1015 385);
FORCEPROP 1 LASTPIN (-1025 375) BN 7
J 2
(-1013 383);
DISPLAY 0.680851 (-1013 383);
PAINT GREEN (-1013 383);
FORCEPROP 2 LAST CDS_LIB standard
J 0
(-1075 375);
DISPLAY INVISIBLE (-1075 375);
FORCEPROP 1 LAST BODY_TYPE PLUMBING
J 2
(-1075 425);
DISPLAY 0.872340 (-1075 425);
PAINT GREEN (-1075 425);
DISPLAY INVISIBLE (-1075 425);
FORCEPROP 1 LAST HDL_TAP TRUE
J 2
(-1400 250);
DISPLAY 0.872340 (-1400 250);
DISPLAY INVISIBLE (-1400 250);
FORCEPROP 1 LAST PATH I17
J 2
(-1073 375);
DISPLAY 0.872340 (-1073 375);
PAINT GREEN (-1073 375);
DISPLAY INVISIBLE (-1073 375);
FORCEADD TAP..1
R 2
(-1075 425);
FORCEPROP 3 LASTPIN (-1025 425) SIG_NAME M_E_CPU1_SB_DQ<0>
J 0
(-1015 435);
DISPLAY 0.659574 (-1015 435);
PAINT MONO (-1015 435);
DISPLAY INVISIBLE (-1015 435);
FORCEPROP 1 LASTPIN (-1025 425) BN 0
J 2
(-1013 433);
DISPLAY 0.680851 (-1013 433);
PAINT GREEN (-1013 433);
FORCEPROP 2 LAST CDS_LIB standard
J 0
(-1075 425);
DISPLAY INVISIBLE (-1075 425);
FORCEPROP 1 LAST BODY_TYPE PLUMBING
J 2
(-1075 475);
DISPLAY 0.872340 (-1075 475);
PAINT GREEN (-1075 475);
DISPLAY INVISIBLE (-1075 475);
FORCEPROP 1 LAST HDL_TAP TRUE
J 2
(-1400 300);
DISPLAY 0.872340 (-1400 300);
DISPLAY INVISIBLE (-1400 300);
FORCEPROP 1 LAST PATH I18
J 2
(-1073 425);
DISPLAY 0.872340 (-1073 425);
PAINT GREEN (-1073 425);
DISPLAY INVISIBLE (-1073 425);
FORCEADD TAP..1
R 2
(-1075 475);
FORCEPROP 3 LASTPIN (-1025 475) SIG_NAME M_E_CPU1_SB_DQ<1>
J 0
(-1015 485);
DISPLAY 0.659574 (-1015 485);
PAINT MONO (-1015 485);
DISPLAY INVISIBLE (-1015 485);
FORCEPROP 1 LASTPIN (-1025 475) BN 1
J 2
(-1013 483);
DISPLAY 0.680851 (-1013 483);
PAINT GREEN (-1013 483);
FORCEPROP 2 LAST CDS_LIB standard
J 0
(-1075 475);
DISPLAY INVISIBLE (-1075 475);
FORCEPROP 1 LAST BODY_TYPE PLUMBING
J 2
(-1075 525);
DISPLAY 0.872340 (-1075 525);
PAINT GREEN (-1075 525);
DISPLAY INVISIBLE (-1075 525);
FORCEPROP 1 LAST HDL_TAP TRUE
J 2
(-1400 350);
DISPLAY 0.872340 (-1400 350);
DISPLAY INVISIBLE (-1400 350);
FORCEPROP 1 LAST PATH I19
J 2
(-1073 475);
DISPLAY 0.872340 (-1073 475);
PAINT GREEN (-1073 475);
DISPLAY INVISIBLE (-1073 475);
FORCEADD OFFPAGE..2
R 2
(-2100 -150);
FORCEPROP 2 LAST $XR1 107 
J 0
(-2475 -150);
DISPLAY 0.638298 (-2475 -150);
PAINT MONO (-2475 -150);
FORCEPROP 2 LAST $XR0 106 
J 0
(-2355 -150);
DISPLAY 0.638298 (-2355 -150);
PAINT MONO (-2355 -150);
FORCEPROP 2 LAST CDS_LIB standard
J 0
(-2100 -150);
PAINT MONO (-2100 -150);
DISPLAY INVISIBLE (-2100 -150);
FORCEPROP 1 LAST OFFPAGE TRUE
J 2
(-2425 -275);
DISPLAY 0.872340 (-2425 -275);
DISPLAY INVISIBLE (-2425 -275);
FORCEPROP 1 LAST COMMENT_BODY TRUE
J 2
(-2055 -245);
DISPLAY 0.872340 (-2055 -245);
PAINT GREEN (-2055 -245);
DISPLAY INVISIBLE (-2055 -245);
FORCEPROP 2 LAST PATH I2
J 0
(-2050 -75);
DISPLAY 1.021277 (-2050 -75);
DISPLAY INVISIBLE (-2050 -75);
FORCEADD TAP..1
R 2
(-1075 525);
FORCEPROP 3 LASTPIN (-1025 525) SIG_NAME M_E_CPU1_SB_DQ<2>
J 0
(-1015 535);
DISPLAY 0.659574 (-1015 535);
PAINT MONO (-1015 535);
DISPLAY INVISIBLE (-1015 535);
FORCEPROP 1 LASTPIN (-1025 525) BN 2
J 2
(-1013 533);
DISPLAY 0.680851 (-1013 533);
PAINT GREEN (-1013 533);
FORCEPROP 2 LAST CDS_LIB standard
J 0
(-1075 525);
DISPLAY INVISIBLE (-1075 525);
FORCEPROP 1 LAST BODY_TYPE PLUMBING
J 2
(-1075 575);
DISPLAY 0.872340 (-1075 575);
PAINT GREEN (-1075 575);
DISPLAY INVISIBLE (-1075 575);
FORCEPROP 1 LAST HDL_TAP TRUE
J 2
(-1400 400);
DISPLAY 0.872340 (-1400 400);
DISPLAY INVISIBLE (-1400 400);
FORCEPROP 1 LAST PATH I20
J 2
(-1073 525);
DISPLAY 0.872340 (-1073 525);
PAINT GREEN (-1073 525);
DISPLAY INVISIBLE (-1073 525);
FORCEADD TAP..1
R 2
(-1075 575);
FORCEPROP 3 LASTPIN (-1025 575) SIG_NAME M_E_CPU1_SB_DQ<3>
J 0
(-1015 585);
DISPLAY 0.659574 (-1015 585);
PAINT MONO (-1015 585);
DISPLAY INVISIBLE (-1015 585);
FORCEPROP 1 LASTPIN (-1025 575) BN 3
J 2
(-1013 583);
DISPLAY 0.680851 (-1013 583);
PAINT GREEN (-1013 583);
FORCEPROP 2 LAST CDS_LIB standard
J 0
(-1075 575);
DISPLAY INVISIBLE (-1075 575);
FORCEPROP 1 LAST BODY_TYPE PLUMBING
J 2
(-1075 625);
DISPLAY 0.872340 (-1075 625);
PAINT GREEN (-1075 625);
DISPLAY INVISIBLE (-1075 625);
FORCEPROP 1 LAST HDL_TAP TRUE
J 2
(-1400 450);
DISPLAY 0.872340 (-1400 450);
DISPLAY INVISIBLE (-1400 450);
FORCEPROP 1 LAST PATH I21
J 2
(-1073 575);
DISPLAY 0.872340 (-1073 575);
PAINT GREEN (-1073 575);
DISPLAY INVISIBLE (-1073 575);
FORCEADD TAP..1
R 2
(-1075 675);
FORCEPROP 3 LASTPIN (-1025 675) SIG_NAME M_E_CPU1_SB_DQ<5>
J 0
(-1015 685);
DISPLAY 0.659574 (-1015 685);
PAINT MONO (-1015 685);
DISPLAY INVISIBLE (-1015 685);
FORCEPROP 1 LASTPIN (-1025 675) BN 5
J 2
(-1013 683);
DISPLAY 0.680851 (-1013 683);
PAINT GREEN (-1013 683);
FORCEPROP 2 LAST CDS_LIB standard
J 0
(-1075 675);
DISPLAY INVISIBLE (-1075 675);
FORCEPROP 1 LAST BODY_TYPE PLUMBING
J 2
(-1075 725);
DISPLAY 0.872340 (-1075 725);
PAINT GREEN (-1075 725);
DISPLAY INVISIBLE (-1075 725);
FORCEPROP 1 LAST HDL_TAP TRUE
J 2
(-1400 550);
DISPLAY 0.872340 (-1400 550);
DISPLAY INVISIBLE (-1400 550);
FORCEPROP 1 LAST PATH I22
J 2
(-1073 675);
DISPLAY 0.872340 (-1073 675);
PAINT GREEN (-1073 675);
DISPLAY INVISIBLE (-1073 675);
FORCEADD TAP..1
R 2
(-1075 625);
FORCEPROP 3 LASTPIN (-1025 625) SIG_NAME M_E_CPU1_SB_DQ<4>
J 0
(-1015 635);
DISPLAY 0.659574 (-1015 635);
PAINT MONO (-1015 635);
DISPLAY INVISIBLE (-1015 635);
FORCEPROP 1 LASTPIN (-1025 625) BN 4
J 2
(-1013 633);
DISPLAY 0.680851 (-1013 633);
PAINT GREEN (-1013 633);
FORCEPROP 2 LAST CDS_LIB standard
J 0
(-1075 625);
DISPLAY INVISIBLE (-1075 625);
FORCEPROP 1 LAST BODY_TYPE PLUMBING
J 2
(-1075 675);
DISPLAY 0.872340 (-1075 675);
PAINT GREEN (-1075 675);
DISPLAY INVISIBLE (-1075 675);
FORCEPROP 1 LAST HDL_TAP TRUE
J 2
(-1400 500);
DISPLAY 0.872340 (-1400 500);
DISPLAY INVISIBLE (-1400 500);
FORCEPROP 1 LAST PATH I23
J 2
(-1073 625);
DISPLAY 0.872340 (-1073 625);
PAINT GREEN (-1073 625);
DISPLAY INVISIBLE (-1073 625);
FORCEADD TAP..1
R 2
(-1075 725);
FORCEPROP 3 LASTPIN (-1025 725) SIG_NAME M_E_CPU1_SB_DQ<6>
J 0
(-1015 735);
DISPLAY 0.659574 (-1015 735);
PAINT MONO (-1015 735);
DISPLAY INVISIBLE (-1015 735);
FORCEPROP 1 LASTPIN (-1025 725) BN 6
J 2
(-1013 733);
DISPLAY 0.680851 (-1013 733);
PAINT GREEN (-1013 733);
FORCEPROP 2 LAST CDS_LIB standard
J 0
(-1075 725);
DISPLAY INVISIBLE (-1075 725);
FORCEPROP 1 LAST BODY_TYPE PLUMBING
J 2
(-1075 775);
DISPLAY 0.872340 (-1075 775);
PAINT GREEN (-1075 775);
DISPLAY INVISIBLE (-1075 775);
FORCEPROP 1 LAST HDL_TAP TRUE
J 2
(-1400 600);
DISPLAY 0.872340 (-1400 600);
DISPLAY INVISIBLE (-1400 600);
FORCEPROP 1 LAST PATH I24
J 2
(-1073 725);
DISPLAY 0.872340 (-1073 725);
PAINT GREEN (-1073 725);
DISPLAY INVISIBLE (-1073 725);
FORCEADD TAP..1
R 2
(-1075 775);
FORCEPROP 3 LASTPIN (-1025 775) SIG_NAME M_E_CPU1_SB_DQ<7>
J 0
(-1015 785);
DISPLAY 0.659574 (-1015 785);
PAINT MONO (-1015 785);
DISPLAY INVISIBLE (-1015 785);
FORCEPROP 1 LASTPIN (-1025 775) BN 7
J 2
(-1013 783);
DISPLAY 0.680851 (-1013 783);
PAINT GREEN (-1013 783);
FORCEPROP 2 LAST CDS_LIB standard
J 0
(-1075 775);
DISPLAY INVISIBLE (-1075 775);
FORCEPROP 1 LAST BODY_TYPE PLUMBING
J 2
(-1075 825);
DISPLAY 0.872340 (-1075 825);
PAINT GREEN (-1075 825);
DISPLAY INVISIBLE (-1075 825);
FORCEPROP 1 LAST HDL_TAP TRUE
J 2
(-1400 650);
DISPLAY 0.872340 (-1400 650);
DISPLAY INVISIBLE (-1400 650);
FORCEPROP 1 LAST PATH I25
J 2
(-1073 775);
DISPLAY 0.872340 (-1073 775);
PAINT GREEN (-1073 775);
DISPLAY INVISIBLE (-1073 775);
FORCEADD TAP..1
R 2
(-1075 825);
FORCEPROP 3 LASTPIN (-1025 825) SIG_NAME M_E_CPU1_SB_DQ<8>
J 0
(-1015 835);
DISPLAY 0.659574 (-1015 835);
PAINT MONO (-1015 835);
DISPLAY INVISIBLE (-1015 835);
FORCEPROP 1 LASTPIN (-1025 825) BN 8
J 2
(-1013 833);
DISPLAY 0.680851 (-1013 833);
PAINT GREEN (-1013 833);
FORCEPROP 2 LAST CDS_LIB standard
J 0
(-1075 825);
DISPLAY INVISIBLE (-1075 825);
FORCEPROP 1 LAST BODY_TYPE PLUMBING
J 2
(-1075 875);
DISPLAY 0.872340 (-1075 875);
PAINT GREEN (-1075 875);
DISPLAY INVISIBLE (-1075 875);
FORCEPROP 1 LAST HDL_TAP TRUE
J 2
(-1400 700);
DISPLAY 0.872340 (-1400 700);
DISPLAY INVISIBLE (-1400 700);
FORCEPROP 1 LAST PATH I26
J 2
(-1073 825);
DISPLAY 0.872340 (-1073 825);
PAINT GREEN (-1073 825);
DISPLAY INVISIBLE (-1073 825);
FORCEADD TAP..1
R 2
(-1075 925);
FORCEPROP 3 LASTPIN (-1025 925) SIG_NAME M_E_CPU1_SB_DQ<10>
J 0
(-1015 935);
DISPLAY 0.659574 (-1015 935);
PAINT MONO (-1015 935);
DISPLAY INVISIBLE (-1015 935);
FORCEPROP 1 LASTPIN (-1025 925) BN 10
J 2
(-1013 933);
DISPLAY 0.680851 (-1013 933);
PAINT GREEN (-1013 933);
FORCEPROP 2 LAST CDS_LIB standard
J 0
(-1075 925);
DISPLAY INVISIBLE (-1075 925);
FORCEPROP 1 LAST BODY_TYPE PLUMBING
J 2
(-1075 975);
DISPLAY 0.872340 (-1075 975);
PAINT GREEN (-1075 975);
DISPLAY INVISIBLE (-1075 975);
FORCEPROP 1 LAST HDL_TAP TRUE
J 2
(-1400 800);
DISPLAY 0.872340 (-1400 800);
DISPLAY INVISIBLE (-1400 800);
FORCEPROP 1 LAST PATH I27
J 2
(-1073 925);
DISPLAY 0.872340 (-1073 925);
PAINT GREEN (-1073 925);
DISPLAY INVISIBLE (-1073 925);
FORCEADD TAP..1
R 2
(-1075 875);
FORCEPROP 3 LASTPIN (-1025 875) SIG_NAME M_E_CPU1_SB_DQ<9>
J 0
(-1015 885);
DISPLAY 0.659574 (-1015 885);
PAINT MONO (-1015 885);
DISPLAY INVISIBLE (-1015 885);
FORCEPROP 1 LASTPIN (-1025 875) BN 9
J 2
(-1013 883);
DISPLAY 0.680851 (-1013 883);
PAINT GREEN (-1013 883);
FORCEPROP 2 LAST CDS_LIB standard
J 0
(-1075 875);
DISPLAY INVISIBLE (-1075 875);
FORCEPROP 1 LAST BODY_TYPE PLUMBING
J 2
(-1075 925);
DISPLAY 0.872340 (-1075 925);
PAINT GREEN (-1075 925);
DISPLAY INVISIBLE (-1075 925);
FORCEPROP 1 LAST HDL_TAP TRUE
J 2
(-1400 750);
DISPLAY 0.872340 (-1400 750);
DISPLAY INVISIBLE (-1400 750);
FORCEPROP 1 LAST PATH I28
J 2
(-1073 875);
DISPLAY 0.872340 (-1073 875);
PAINT GREEN (-1073 875);
DISPLAY INVISIBLE (-1073 875);
FORCEADD TAP..1
R 2
(-1075 975);
FORCEPROP 3 LASTPIN (-1025 975) SIG_NAME M_E_CPU1_SB_DQ<11>
J 0
(-1015 985);
DISPLAY 0.659574 (-1015 985);
PAINT MONO (-1015 985);
DISPLAY INVISIBLE (-1015 985);
FORCEPROP 1 LASTPIN (-1025 975) BN 11
J 2
(-1013 983);
DISPLAY 0.680851 (-1013 983);
PAINT GREEN (-1013 983);
FORCEPROP 2 LAST CDS_LIB standard
J 0
(-1075 975);
DISPLAY INVISIBLE (-1075 975);
FORCEPROP 1 LAST BODY_TYPE PLUMBING
J 2
(-1075 1025);
DISPLAY 0.872340 (-1075 1025);
PAINT GREEN (-1075 1025);
DISPLAY INVISIBLE (-1075 1025);
FORCEPROP 1 LAST HDL_TAP TRUE
J 2
(-1400 850);
DISPLAY 0.872340 (-1400 850);
DISPLAY INVISIBLE (-1400 850);
FORCEPROP 1 LAST PATH I29
J 2
(-1073 975);
DISPLAY 0.872340 (-1073 975);
PAINT GREEN (-1073 975);
DISPLAY INVISIBLE (-1073 975);
FORCEADD TAP..1
R 2
(-1075 -175);
FORCEPROP 3 LASTPIN (-1025 -175) SIG_NAME M_E_CPU1_CLK_DN<1>
J 0
(-1015 -165);
DISPLAY 0.659574 (-1015 -165);
PAINT MONO (-1015 -165);
DISPLAY INVISIBLE (-1015 -165);
FORCEPROP 1 LASTPIN (-1025 -175) BN 1
J 2
(-1013 -167);
DISPLAY 0.680851 (-1013 -167);
PAINT GREEN (-1013 -167);
FORCEPROP 2 LAST CDS_LIB standard
J 0
(-1075 -175);
DISPLAY INVISIBLE (-1075 -175);
FORCEPROP 1 LAST BODY_TYPE PLUMBING
J 2
(-1075 -125);
DISPLAY 0.872340 (-1075 -125);
PAINT GREEN (-1075 -125);
DISPLAY INVISIBLE (-1075 -125);
FORCEPROP 1 LAST HDL_TAP TRUE
J 2
(-1400 -300);
DISPLAY 0.872340 (-1400 -300);
DISPLAY INVISIBLE (-1400 -300);
FORCEPROP 1 LAST PATH I3
J 2
(-1073 -175);
DISPLAY 0.872340 (-1073 -175);
PAINT GREEN (-1073 -175);
DISPLAY INVISIBLE (-1073 -175);
FORCEADD TAP..1
R 2
(-1075 1025);
FORCEPROP 3 LASTPIN (-1025 1025) SIG_NAME M_E_CPU1_SB_DQ<12>
J 0
(-1015 1035);
DISPLAY 0.659574 (-1015 1035);
PAINT MONO (-1015 1035);
DISPLAY INVISIBLE (-1015 1035);
FORCEPROP 1 LASTPIN (-1025 1025) BN 12
J 2
(-1013 1033);
DISPLAY 0.680851 (-1013 1033);
PAINT GREEN (-1013 1033);
FORCEPROP 2 LAST CDS_LIB standard
J 0
(-1075 1025);
DISPLAY INVISIBLE (-1075 1025);
FORCEPROP 1 LAST BODY_TYPE PLUMBING
J 2
(-1075 1075);
DISPLAY 0.872340 (-1075 1075);
PAINT GREEN (-1075 1075);
DISPLAY INVISIBLE (-1075 1075);
FORCEPROP 1 LAST HDL_TAP TRUE
J 2
(-1400 900);
DISPLAY 0.872340 (-1400 900);
DISPLAY INVISIBLE (-1400 900);
FORCEPROP 1 LAST PATH I30
J 2
(-1073 1025);
DISPLAY 0.872340 (-1073 1025);
PAINT GREEN (-1073 1025);
DISPLAY INVISIBLE (-1073 1025);
FORCEADD TAP..1
R 2
(-1075 1075);
FORCEPROP 3 LASTPIN (-1025 1075) SIG_NAME M_E_CPU1_SB_DQ<13>
J 0
(-1015 1085);
DISPLAY 0.659574 (-1015 1085);
PAINT MONO (-1015 1085);
DISPLAY INVISIBLE (-1015 1085);
FORCEPROP 1 LASTPIN (-1025 1075) BN 13
J 2
(-1013 1083);
DISPLAY 0.680851 (-1013 1083);
PAINT GREEN (-1013 1083);
FORCEPROP 2 LAST CDS_LIB standard
J 0
(-1075 1075);
DISPLAY INVISIBLE (-1075 1075);
FORCEPROP 1 LAST BODY_TYPE PLUMBING
J 2
(-1075 1125);
DISPLAY 0.872340 (-1075 1125);
PAINT GREEN (-1075 1125);
DISPLAY INVISIBLE (-1075 1125);
FORCEPROP 1 LAST HDL_TAP TRUE
J 2
(-1400 950);
DISPLAY 0.872340 (-1400 950);
DISPLAY INVISIBLE (-1400 950);
FORCEPROP 1 LAST PATH I31
J 2
(-1073 1075);
DISPLAY 0.872340 (-1073 1075);
PAINT GREEN (-1073 1075);
DISPLAY INVISIBLE (-1073 1075);
FORCEADD TAP..1
R 2
(-1075 1125);
FORCEPROP 3 LASTPIN (-1025 1125) SIG_NAME M_E_CPU1_SB_DQ<14>
J 0
(-1015 1135);
DISPLAY 0.659574 (-1015 1135);
PAINT MONO (-1015 1135);
DISPLAY INVISIBLE (-1015 1135);
FORCEPROP 1 LASTPIN (-1025 1125) BN 14
J 2
(-1013 1133);
DISPLAY 0.680851 (-1013 1133);
PAINT GREEN (-1013 1133);
FORCEPROP 2 LAST CDS_LIB standard
J 0
(-1075 1125);
DISPLAY INVISIBLE (-1075 1125);
FORCEPROP 1 LAST BODY_TYPE PLUMBING
J 2
(-1075 1175);
DISPLAY 0.872340 (-1075 1175);
PAINT GREEN (-1075 1175);
DISPLAY INVISIBLE (-1075 1175);
FORCEPROP 1 LAST HDL_TAP TRUE
J 2
(-1400 1000);
DISPLAY 0.872340 (-1400 1000);
DISPLAY INVISIBLE (-1400 1000);
FORCEPROP 1 LAST PATH I32
J 2
(-1073 1125);
DISPLAY 0.872340 (-1073 1125);
PAINT GREEN (-1073 1125);
DISPLAY INVISIBLE (-1073 1125);
FORCEADD TAP..1
R 2
(-1075 1175);
FORCEPROP 3 LASTPIN (-1025 1175) SIG_NAME M_E_CPU1_SB_DQ<15>
J 0
(-1015 1185);
DISPLAY 0.659574 (-1015 1185);
PAINT MONO (-1015 1185);
DISPLAY INVISIBLE (-1015 1185);
FORCEPROP 1 LASTPIN (-1025 1175) BN 15
J 2
(-1013 1183);
DISPLAY 0.680851 (-1013 1183);
PAINT GREEN (-1013 1183);
FORCEPROP 2 LAST CDS_LIB standard
J 0
(-1075 1175);
DISPLAY INVISIBLE (-1075 1175);
FORCEPROP 1 LAST BODY_TYPE PLUMBING
J 2
(-1075 1225);
DISPLAY 0.872340 (-1075 1225);
PAINT GREEN (-1075 1225);
DISPLAY INVISIBLE (-1075 1225);
FORCEPROP 1 LAST HDL_TAP TRUE
J 2
(-1400 1050);
DISPLAY 0.872340 (-1400 1050);
DISPLAY INVISIBLE (-1400 1050);
FORCEPROP 1 LAST PATH I33
J 2
(-1073 1175);
DISPLAY 0.872340 (-1073 1175);
PAINT GREEN (-1073 1175);
DISPLAY INVISIBLE (-1073 1175);
FORCEADD TAP..1
R 2
(-1075 1225);
FORCEPROP 3 LASTPIN (-1025 1225) SIG_NAME M_E_CPU1_SB_DQ<16>
J 0
(-1015 1235);
DISPLAY 0.659574 (-1015 1235);
PAINT MONO (-1015 1235);
DISPLAY INVISIBLE (-1015 1235);
FORCEPROP 1 LASTPIN (-1025 1225) BN 16
J 2
(-1013 1233);
DISPLAY 0.680851 (-1013 1233);
PAINT GREEN (-1013 1233);
FORCEPROP 2 LAST CDS_LIB standard
J 0
(-1075 1225);
DISPLAY INVISIBLE (-1075 1225);
FORCEPROP 1 LAST BODY_TYPE PLUMBING
J 2
(-1075 1275);
DISPLAY 0.872340 (-1075 1275);
PAINT GREEN (-1075 1275);
DISPLAY INVISIBLE (-1075 1275);
FORCEPROP 1 LAST HDL_TAP TRUE
J 2
(-1400 1100);
DISPLAY 0.872340 (-1400 1100);
DISPLAY INVISIBLE (-1400 1100);
FORCEPROP 1 LAST PATH I34
J 2
(-1073 1225);
DISPLAY 0.872340 (-1073 1225);
PAINT GREEN (-1073 1225);
DISPLAY INVISIBLE (-1073 1225);
FORCEADD TAP..1
R 2
(-1075 1325);
FORCEPROP 3 LASTPIN (-1025 1325) SIG_NAME M_E_CPU1_SB_DQ<18>
J 0
(-1015 1335);
DISPLAY 0.659574 (-1015 1335);
PAINT MONO (-1015 1335);
DISPLAY INVISIBLE (-1015 1335);
FORCEPROP 1 LASTPIN (-1025 1325) BN 18
J 2
(-1013 1333);
DISPLAY 0.680851 (-1013 1333);
PAINT GREEN (-1013 1333);
FORCEPROP 2 LAST CDS_LIB standard
J 0
(-1075 1325);
DISPLAY INVISIBLE (-1075 1325);
FORCEPROP 1 LAST BODY_TYPE PLUMBING
J 2
(-1075 1375);
DISPLAY 0.872340 (-1075 1375);
PAINT GREEN (-1075 1375);
DISPLAY INVISIBLE (-1075 1375);
FORCEPROP 1 LAST HDL_TAP TRUE
J 2
(-1400 1200);
DISPLAY 0.872340 (-1400 1200);
DISPLAY INVISIBLE (-1400 1200);
FORCEPROP 1 LAST PATH I35
J 2
(-1073 1325);
DISPLAY 0.872340 (-1073 1325);
PAINT GREEN (-1073 1325);
DISPLAY INVISIBLE (-1073 1325);
FORCEADD TAP..1
R 2
(-1075 1275);
FORCEPROP 3 LASTPIN (-1025 1275) SIG_NAME M_E_CPU1_SB_DQ<17>
J 0
(-1015 1285);
DISPLAY 0.659574 (-1015 1285);
PAINT MONO (-1015 1285);
DISPLAY INVISIBLE (-1015 1285);
FORCEPROP 1 LASTPIN (-1025 1275) BN 17
J 2
(-1013 1283);
DISPLAY 0.680851 (-1013 1283);
PAINT GREEN (-1013 1283);
FORCEPROP 2 LAST CDS_LIB standard
J 0
(-1075 1275);
DISPLAY INVISIBLE (-1075 1275);
FORCEPROP 1 LAST BODY_TYPE PLUMBING
J 2
(-1075 1325);
DISPLAY 0.872340 (-1075 1325);
PAINT GREEN (-1075 1325);
DISPLAY INVISIBLE (-1075 1325);
FORCEPROP 1 LAST HDL_TAP TRUE
J 2
(-1400 1150);
DISPLAY 0.872340 (-1400 1150);
DISPLAY INVISIBLE (-1400 1150);
FORCEPROP 1 LAST PATH I36
J 2
(-1073 1275);
DISPLAY 0.872340 (-1073 1275);
PAINT GREEN (-1073 1275);
DISPLAY INVISIBLE (-1073 1275);
FORCEADD TAP..1
R 2
(-1075 1375);
FORCEPROP 3 LASTPIN (-1025 1375) SIG_NAME M_E_CPU1_SB_DQ<19>
J 0
(-1015 1385);
DISPLAY 0.659574 (-1015 1385);
PAINT MONO (-1015 1385);
DISPLAY INVISIBLE (-1015 1385);
FORCEPROP 1 LASTPIN (-1025 1375) BN 19
J 2
(-1013 1383);
DISPLAY 0.680851 (-1013 1383);
PAINT GREEN (-1013 1383);
FORCEPROP 2 LAST CDS_LIB standard
J 0
(-1075 1375);
DISPLAY INVISIBLE (-1075 1375);
FORCEPROP 1 LAST BODY_TYPE PLUMBING
J 2
(-1075 1425);
DISPLAY 0.872340 (-1075 1425);
PAINT GREEN (-1075 1425);
DISPLAY INVISIBLE (-1075 1425);
FORCEPROP 1 LAST HDL_TAP TRUE
J 2
(-1400 1250);
DISPLAY 0.872340 (-1400 1250);
DISPLAY INVISIBLE (-1400 1250);
FORCEPROP 1 LAST PATH I37
J 2
(-1073 1375);
DISPLAY 0.872340 (-1073 1375);
PAINT GREEN (-1073 1375);
DISPLAY INVISIBLE (-1073 1375);
FORCEADD TAP..1
R 2
(-1075 1425);
FORCEPROP 3 LASTPIN (-1025 1425) SIG_NAME M_E_CPU1_SB_DQ<20>
J 0
(-1015 1435);
DISPLAY 0.659574 (-1015 1435);
PAINT MONO (-1015 1435);
DISPLAY INVISIBLE (-1015 1435);
FORCEPROP 1 LASTPIN (-1025 1425) BN 20
J 2
(-1013 1433);
DISPLAY 0.680851 (-1013 1433);
PAINT GREEN (-1013 1433);
FORCEPROP 2 LAST CDS_LIB standard
J 0
(-1075 1425);
DISPLAY INVISIBLE (-1075 1425);
FORCEPROP 1 LAST BODY_TYPE PLUMBING
J 2
(-1075 1475);
DISPLAY 0.872340 (-1075 1475);
PAINT GREEN (-1075 1475);
DISPLAY INVISIBLE (-1075 1475);
FORCEPROP 1 LAST HDL_TAP TRUE
J 2
(-1400 1300);
DISPLAY 0.872340 (-1400 1300);
DISPLAY INVISIBLE (-1400 1300);
FORCEPROP 1 LAST PATH I38
J 2
(-1073 1425);
DISPLAY 0.872340 (-1073 1425);
PAINT GREEN (-1073 1425);
DISPLAY INVISIBLE (-1073 1425);
FORCEADD TAP..1
R 2
(-1075 1475);
FORCEPROP 3 LASTPIN (-1025 1475) SIG_NAME M_E_CPU1_SB_DQ<21>
J 0
(-1015 1485);
DISPLAY 0.659574 (-1015 1485);
PAINT MONO (-1015 1485);
DISPLAY INVISIBLE (-1015 1485);
FORCEPROP 1 LASTPIN (-1025 1475) BN 21
J 2
(-1013 1483);
DISPLAY 0.680851 (-1013 1483);
PAINT GREEN (-1013 1483);
FORCEPROP 2 LAST CDS_LIB standard
J 0
(-1075 1475);
DISPLAY INVISIBLE (-1075 1475);
FORCEPROP 1 LAST BODY_TYPE PLUMBING
J 2
(-1075 1525);
DISPLAY 0.872340 (-1075 1525);
PAINT GREEN (-1075 1525);
DISPLAY INVISIBLE (-1075 1525);
FORCEPROP 1 LAST HDL_TAP TRUE
J 2
(-1400 1350);
DISPLAY 0.872340 (-1400 1350);
DISPLAY INVISIBLE (-1400 1350);
FORCEPROP 1 LAST PATH I39
J 2
(-1073 1475);
DISPLAY 0.872340 (-1073 1475);
PAINT GREEN (-1073 1475);
DISPLAY INVISIBLE (-1073 1475);
FORCEADD TAP..1
R 2
(-1075 -225);
FORCEPROP 3 LASTPIN (-1025 -225) SIG_NAME M_E_CPU1_CLK_DN<0>
J 0
(-1015 -215);
DISPLAY 0.659574 (-1015 -215);
PAINT MONO (-1015 -215);
DISPLAY INVISIBLE (-1015 -215);
FORCEPROP 1 LASTPIN (-1025 -225) BN 0
J 2
(-1013 -217);
DISPLAY 0.680851 (-1013 -217);
PAINT GREEN (-1013 -217);
FORCEPROP 2 LAST CDS_LIB standard
J 0
(-1075 -225);
DISPLAY INVISIBLE (-1075 -225);
FORCEPROP 1 LAST BODY_TYPE PLUMBING
J 2
(-1075 -175);
DISPLAY 0.872340 (-1075 -175);
PAINT GREEN (-1075 -175);
DISPLAY INVISIBLE (-1075 -175);
FORCEPROP 1 LAST HDL_TAP TRUE
J 2
(-1400 -350);
DISPLAY 0.872340 (-1400 -350);
DISPLAY INVISIBLE (-1400 -350);
FORCEPROP 1 LAST PATH I4
J 2
(-1073 -225);
DISPLAY 0.872340 (-1073 -225);
PAINT GREEN (-1073 -225);
DISPLAY INVISIBLE (-1073 -225);
FORCEADD TAP..1
R 2
(-1075 1575);
FORCEPROP 3 LASTPIN (-1025 1575) SIG_NAME M_E_CPU1_SB_DQ<23>
J 0
(-1015 1585);
DISPLAY 0.659574 (-1015 1585);
PAINT MONO (-1015 1585);
DISPLAY INVISIBLE (-1015 1585);
FORCEPROP 1 LASTPIN (-1025 1575) BN 23
J 2
(-1013 1583);
DISPLAY 0.680851 (-1013 1583);
PAINT GREEN (-1013 1583);
FORCEPROP 2 LAST CDS_LIB standard
J 0
(-1075 1575);
DISPLAY INVISIBLE (-1075 1575);
FORCEPROP 1 LAST BODY_TYPE PLUMBING
J 2
(-1075 1625);
DISPLAY 0.872340 (-1075 1625);
PAINT GREEN (-1075 1625);
DISPLAY INVISIBLE (-1075 1625);
FORCEPROP 1 LAST HDL_TAP TRUE
J 2
(-1400 1450);
DISPLAY 0.872340 (-1400 1450);
DISPLAY INVISIBLE (-1400 1450);
FORCEPROP 1 LAST PATH I40
J 2
(-1073 1575);
DISPLAY 0.872340 (-1073 1575);
PAINT GREEN (-1073 1575);
DISPLAY INVISIBLE (-1073 1575);
FORCEADD TAP..1
R 2
(-1075 1525);
FORCEPROP 3 LASTPIN (-1025 1525) SIG_NAME M_E_CPU1_SB_DQ<22>
J 0
(-1015 1535);
DISPLAY 0.659574 (-1015 1535);
PAINT MONO (-1015 1535);
DISPLAY INVISIBLE (-1015 1535);
FORCEPROP 1 LASTPIN (-1025 1525) BN 22
J 2
(-1013 1533);
DISPLAY 0.680851 (-1013 1533);
PAINT GREEN (-1013 1533);
FORCEPROP 2 LAST CDS_LIB standard
J 0
(-1075 1525);
DISPLAY INVISIBLE (-1075 1525);
FORCEPROP 1 LAST BODY_TYPE PLUMBING
J 2
(-1075 1575);
DISPLAY 0.872340 (-1075 1575);
PAINT GREEN (-1075 1575);
DISPLAY INVISIBLE (-1075 1575);
FORCEPROP 1 LAST HDL_TAP TRUE
J 2
(-1400 1400);
DISPLAY 0.872340 (-1400 1400);
DISPLAY INVISIBLE (-1400 1400);
FORCEPROP 1 LAST PATH I41
J 2
(-1073 1525);
DISPLAY 0.872340 (-1073 1525);
PAINT GREEN (-1073 1525);
DISPLAY INVISIBLE (-1073 1525);
FORCEADD TAP..1
R 2
(-1075 1625);
FORCEPROP 3 LASTPIN (-1025 1625) SIG_NAME M_E_CPU1_SB_DQ<24>
J 0
(-1015 1635);
DISPLAY 0.659574 (-1015 1635);
PAINT MONO (-1015 1635);
DISPLAY INVISIBLE (-1015 1635);
FORCEPROP 1 LASTPIN (-1025 1625) BN 24
J 2
(-1013 1633);
DISPLAY 0.680851 (-1013 1633);
PAINT GREEN (-1013 1633);
FORCEPROP 2 LAST CDS_LIB standard
J 0
(-1075 1625);
DISPLAY INVISIBLE (-1075 1625);
FORCEPROP 1 LAST BODY_TYPE PLUMBING
J 2
(-1075 1675);
DISPLAY 0.872340 (-1075 1675);
PAINT GREEN (-1075 1675);
DISPLAY INVISIBLE (-1075 1675);
FORCEPROP 1 LAST HDL_TAP TRUE
J 2
(-1400 1500);
DISPLAY 0.872340 (-1400 1500);
DISPLAY INVISIBLE (-1400 1500);
FORCEPROP 1 LAST PATH I42
J 2
(-1073 1625);
DISPLAY 0.872340 (-1073 1625);
PAINT GREEN (-1073 1625);
DISPLAY INVISIBLE (-1073 1625);
FORCEADD TAP..1
R 2
(-1075 1675);
FORCEPROP 3 LASTPIN (-1025 1675) SIG_NAME M_E_CPU1_SB_DQ<25>
J 0
(-1015 1685);
DISPLAY 0.659574 (-1015 1685);
PAINT MONO (-1015 1685);
DISPLAY INVISIBLE (-1015 1685);
FORCEPROP 1 LASTPIN (-1025 1675) BN 25
J 2
(-1013 1683);
DISPLAY 0.680851 (-1013 1683);
PAINT GREEN (-1013 1683);
FORCEPROP 2 LAST CDS_LIB standard
J 0
(-1075 1675);
DISPLAY INVISIBLE (-1075 1675);
FORCEPROP 1 LAST BODY_TYPE PLUMBING
J 2
(-1075 1725);
DISPLAY 0.872340 (-1075 1725);
PAINT GREEN (-1075 1725);
DISPLAY INVISIBLE (-1075 1725);
FORCEPROP 1 LAST HDL_TAP TRUE
J 2
(-1400 1550);
DISPLAY 0.872340 (-1400 1550);
DISPLAY INVISIBLE (-1400 1550);
FORCEPROP 1 LAST PATH I43
J 2
(-1073 1675);
DISPLAY 0.872340 (-1073 1675);
PAINT GREEN (-1073 1675);
DISPLAY INVISIBLE (-1073 1675);
FORCEADD TAP..1
R 2
(-1075 1725);
FORCEPROP 3 LASTPIN (-1025 1725) SIG_NAME M_E_CPU1_SB_DQ<26>
J 0
(-1015 1735);
DISPLAY 0.659574 (-1015 1735);
PAINT MONO (-1015 1735);
DISPLAY INVISIBLE (-1015 1735);
FORCEPROP 1 LASTPIN (-1025 1725) BN 26
J 2
(-1013 1733);
DISPLAY 0.680851 (-1013 1733);
PAINT GREEN (-1013 1733);
FORCEPROP 2 LAST CDS_LIB standard
J 0
(-1075 1725);
DISPLAY INVISIBLE (-1075 1725);
FORCEPROP 1 LAST BODY_TYPE PLUMBING
J 2
(-1075 1775);
DISPLAY 0.872340 (-1075 1775);
PAINT GREEN (-1075 1775);
DISPLAY INVISIBLE (-1075 1775);
FORCEPROP 1 LAST HDL_TAP TRUE
J 2
(-1400 1600);
DISPLAY 0.872340 (-1400 1600);
DISPLAY INVISIBLE (-1400 1600);
FORCEPROP 1 LAST PATH I44
J 2
(-1073 1725);
DISPLAY 0.872340 (-1073 1725);
PAINT GREEN (-1073 1725);
DISPLAY INVISIBLE (-1073 1725);
FORCEADD TAP..1
R 2
(-1075 1825);
FORCEPROP 3 LASTPIN (-1025 1825) SIG_NAME M_E_CPU1_SB_DQ<28>
J 0
(-1015 1835);
DISPLAY 0.659574 (-1015 1835);
PAINT MONO (-1015 1835);
DISPLAY INVISIBLE (-1015 1835);
FORCEPROP 1 LASTPIN (-1025 1825) BN 28
J 2
(-1013 1833);
DISPLAY 0.680851 (-1013 1833);
PAINT GREEN (-1013 1833);
FORCEPROP 2 LAST CDS_LIB standard
J 0
(-1075 1825);
DISPLAY INVISIBLE (-1075 1825);
FORCEPROP 1 LAST BODY_TYPE PLUMBING
J 2
(-1075 1875);
DISPLAY 0.872340 (-1075 1875);
PAINT GREEN (-1075 1875);
DISPLAY INVISIBLE (-1075 1875);
FORCEPROP 1 LAST HDL_TAP TRUE
J 2
(-1400 1700);
DISPLAY 0.872340 (-1400 1700);
DISPLAY INVISIBLE (-1400 1700);
FORCEPROP 1 LAST PATH I45
J 2
(-1073 1825);
DISPLAY 0.872340 (-1073 1825);
PAINT GREEN (-1073 1825);
DISPLAY INVISIBLE (-1073 1825);
FORCEADD TAP..1
R 2
(-1075 1775);
FORCEPROP 3 LASTPIN (-1025 1775) SIG_NAME M_E_CPU1_SB_DQ<27>
J 0
(-1015 1785);
DISPLAY 0.659574 (-1015 1785);
PAINT MONO (-1015 1785);
DISPLAY INVISIBLE (-1015 1785);
FORCEPROP 1 LASTPIN (-1025 1775) BN 27
J 2
(-1013 1783);
DISPLAY 0.680851 (-1013 1783);
PAINT GREEN (-1013 1783);
FORCEPROP 2 LAST CDS_LIB standard
J 0
(-1075 1775);
DISPLAY INVISIBLE (-1075 1775);
FORCEPROP 1 LAST BODY_TYPE PLUMBING
J 2
(-1075 1825);
DISPLAY 0.872340 (-1075 1825);
PAINT GREEN (-1075 1825);
DISPLAY INVISIBLE (-1075 1825);
FORCEPROP 1 LAST HDL_TAP TRUE
J 2
(-1400 1650);
DISPLAY 0.872340 (-1400 1650);
DISPLAY INVISIBLE (-1400 1650);
FORCEPROP 1 LAST PATH I46
J 2
(-1073 1775);
DISPLAY 0.872340 (-1073 1775);
PAINT GREEN (-1073 1775);
DISPLAY INVISIBLE (-1073 1775);
FORCEADD TAP..1
R 2
(-1075 1875);
FORCEPROP 3 LASTPIN (-1025 1875) SIG_NAME M_E_CPU1_SB_DQ<29>
J 0
(-1015 1885);
DISPLAY 0.659574 (-1015 1885);
PAINT MONO (-1015 1885);
DISPLAY INVISIBLE (-1015 1885);
FORCEPROP 1 LASTPIN (-1025 1875) BN 29
J 2
(-1013 1883);
DISPLAY 0.680851 (-1013 1883);
PAINT GREEN (-1013 1883);
FORCEPROP 2 LAST CDS_LIB standard
J 0
(-1075 1875);
DISPLAY INVISIBLE (-1075 1875);
FORCEPROP 1 LAST BODY_TYPE PLUMBING
J 2
(-1075 1925);
DISPLAY 0.872340 (-1075 1925);
PAINT GREEN (-1075 1925);
DISPLAY INVISIBLE (-1075 1925);
FORCEPROP 1 LAST HDL_TAP TRUE
J 2
(-1400 1750);
DISPLAY 0.872340 (-1400 1750);
DISPLAY INVISIBLE (-1400 1750);
FORCEPROP 1 LAST PATH I47
J 2
(-1073 1875);
DISPLAY 0.872340 (-1073 1875);
PAINT GREEN (-1073 1875);
DISPLAY INVISIBLE (-1073 1875);
FORCEADD TAP..1
R 2
(-1075 1925);
FORCEPROP 3 LASTPIN (-1025 1925) SIG_NAME M_E_CPU1_SB_DQ<30>
J 0
(-1015 1935);
DISPLAY 0.659574 (-1015 1935);
PAINT MONO (-1015 1935);
DISPLAY INVISIBLE (-1015 1935);
FORCEPROP 1 LASTPIN (-1025 1925) BN 30
J 2
(-1013 1933);
DISPLAY 0.680851 (-1013 1933);
PAINT GREEN (-1013 1933);
FORCEPROP 2 LAST CDS_LIB standard
J 0
(-1075 1925);
DISPLAY INVISIBLE (-1075 1925);
FORCEPROP 1 LAST BODY_TYPE PLUMBING
J 2
(-1075 1975);
DISPLAY 0.872340 (-1075 1975);
PAINT GREEN (-1075 1975);
DISPLAY INVISIBLE (-1075 1975);
FORCEPROP 1 LAST HDL_TAP TRUE
J 2
(-1400 1800);
DISPLAY 0.872340 (-1400 1800);
DISPLAY INVISIBLE (-1400 1800);
FORCEPROP 1 LAST PATH I48
J 2
(-1073 1925);
DISPLAY 0.872340 (-1073 1925);
PAINT GREEN (-1073 1925);
DISPLAY INVISIBLE (-1073 1925);
FORCEADD TAP..1
R 2
(-1075 1975);
FORCEPROP 3 LASTPIN (-1025 1975) SIG_NAME M_E_CPU1_SB_DQ<31>
J 0
(-1015 1985);
DISPLAY 0.659574 (-1015 1985);
PAINT MONO (-1015 1985);
DISPLAY INVISIBLE (-1015 1985);
FORCEPROP 1 LASTPIN (-1025 1975) BN 31
J 2
(-1013 1983);
DISPLAY 0.680851 (-1013 1983);
PAINT GREEN (-1013 1983);
FORCEPROP 2 LAST CDS_LIB standard
J 0
(-1075 1975);
DISPLAY INVISIBLE (-1075 1975);
FORCEPROP 1 LAST BODY_TYPE PLUMBING
J 2
(-1075 2025);
DISPLAY 0.872340 (-1075 2025);
PAINT GREEN (-1075 2025);
DISPLAY INVISIBLE (-1075 2025);
FORCEPROP 1 LAST HDL_TAP TRUE
J 2
(-1400 1850);
DISPLAY 0.872340 (-1400 1850);
DISPLAY INVISIBLE (-1400 1850);
FORCEPROP 1 LAST PATH I49
J 2
(-1073 1975);
DISPLAY 0.872340 (-1073 1975);
PAINT GREEN (-1073 1975);
DISPLAY INVISIBLE (-1073 1975);
FORCEADD TAP..1
R 2
(-1075 -125);
FORCEPROP 3 LASTPIN (-1025 -125) SIG_NAME M_E_CPU1_CLK_DP<0>
J 0
(-1015 -115);
DISPLAY 0.659574 (-1015 -115);
PAINT MONO (-1015 -115);
DISPLAY INVISIBLE (-1015 -115);
FORCEPROP 1 LASTPIN (-1025 -125) BN 0
J 2
(-1013 -117);
DISPLAY 0.680851 (-1013 -117);
PAINT GREEN (-1013 -117);
FORCEPROP 2 LAST CDS_LIB standard
J 0
(-1075 -125);
DISPLAY INVISIBLE (-1075 -125);
FORCEPROP 1 LAST BODY_TYPE PLUMBING
J 2
(-1075 -75);
DISPLAY 0.872340 (-1075 -75);
PAINT GREEN (-1075 -75);
DISPLAY INVISIBLE (-1075 -75);
FORCEPROP 1 LAST HDL_TAP TRUE
J 2
(-1400 -250);
DISPLAY 0.872340 (-1400 -250);
DISPLAY INVISIBLE (-1400 -250);
FORCEPROP 1 LAST PATH I5
J 2
(-1073 -125);
DISPLAY 0.872340 (-1073 -125);
PAINT GREEN (-1073 -125);
DISPLAY INVISIBLE (-1073 -125);
FORCEADD OFFPAGE..3
R 2
(-2100 2400);
FORCEPROP 2 LAST $XR1 107 
J 0
(-2530 2400);
DISPLAY 0.638298 (-2530 2400);
PAINT MONO (-2530 2400);
FORCEPROP 2 LAST $XR0 106 
J 0
(-2410 2400);
DISPLAY 0.638298 (-2410 2400);
PAINT MONO (-2410 2400);
FORCEPROP 2 LAST CDS_LIB standard
J 0
(-2100 2400);
DISPLAY INVISIBLE (-2100 2400);
FORCEPROP 1 LAST OFFPAGE TRUE
J 2
(-2425 2275);
DISPLAY 0.872340 (-2425 2275);
DISPLAY INVISIBLE (-2425 2275);
FORCEPROP 1 LAST COMMENT_BODY TRUE
J 2
(-2050 2300);
DISPLAY 0.872340 (-2050 2300);
PAINT GREEN (-2050 2300);
DISPLAY INVISIBLE (-2050 2300);
FORCEPROP 2 LAST PATH I50
J 0
(-2050 2475);
DISPLAY 1.021277 (-2050 2475);
DISPLAY INVISIBLE (-2050 2475);
FORCEADD OFFPAGE..3
R 2
(-2100 4000);
FORCEPROP 2 LAST $XR1 107 
J 0
(-2530 4000);
DISPLAY 0.638298 (-2530 4000);
PAINT MONO (-2530 4000);
FORCEPROP 2 LAST $XR0 106 
J 0
(-2410 4000);
DISPLAY 0.638298 (-2410 4000);
PAINT MONO (-2410 4000);
FORCEPROP 2 LAST CDS_LIB standard
J 0
(-2100 4000);
DISPLAY INVISIBLE (-2100 4000);
FORCEPROP 1 LAST OFFPAGE TRUE
J 2
(-2425 3875);
DISPLAY 0.872340 (-2425 3875);
DISPLAY INVISIBLE (-2425 3875);
FORCEPROP 1 LAST COMMENT_BODY TRUE
J 2
(-2050 3900);
DISPLAY 0.872340 (-2050 3900);
PAINT GREEN (-2050 3900);
DISPLAY INVISIBLE (-2050 3900);
FORCEPROP 2 LAST PATH I51
J 0
(-2050 4075);
DISPLAY 1.021277 (-2050 4075);
DISPLAY INVISIBLE (-2050 4075);
FORCEADD TAP..1
R 2
(-1075 2075);
FORCEPROP 3 LASTPIN (-1025 2075) SIG_NAME M_E_CPU1_SA_CB<1>
J 0
(-1015 2085);
DISPLAY 0.659574 (-1015 2085);
PAINT MONO (-1015 2085);
DISPLAY INVISIBLE (-1015 2085);
FORCEPROP 1 LASTPIN (-1025 2075) BN 1
J 2
(-1013 2083);
DISPLAY 0.680851 (-1013 2083);
PAINT GREEN (-1013 2083);
FORCEPROP 2 LAST CDS_LIB standard
J 0
(-1075 2075);
DISPLAY INVISIBLE (-1075 2075);
FORCEPROP 1 LAST BODY_TYPE PLUMBING
J 2
(-1075 2125);
DISPLAY 0.872340 (-1075 2125);
PAINT GREEN (-1075 2125);
DISPLAY INVISIBLE (-1075 2125);
FORCEPROP 1 LAST HDL_TAP TRUE
J 2
(-1400 1950);
DISPLAY 0.872340 (-1400 1950);
DISPLAY INVISIBLE (-1400 1950);
FORCEPROP 1 LAST PATH I52
J 2
(-1073 2075);
DISPLAY 0.872340 (-1073 2075);
PAINT GREEN (-1073 2075);
DISPLAY INVISIBLE (-1073 2075);
FORCEADD TAP..1
R 2
(-1075 2025);
FORCEPROP 3 LASTPIN (-1025 2025) SIG_NAME M_E_CPU1_SA_CB<0>
J 0
(-1015 2035);
DISPLAY 0.659574 (-1015 2035);
PAINT MONO (-1015 2035);
DISPLAY INVISIBLE (-1015 2035);
FORCEPROP 1 LASTPIN (-1025 2025) BN 0
J 2
(-1013 2033);
DISPLAY 0.680851 (-1013 2033);
PAINT GREEN (-1013 2033);
FORCEPROP 2 LAST CDS_LIB standard
J 0
(-1075 2025);
DISPLAY INVISIBLE (-1075 2025);
FORCEPROP 1 LAST BODY_TYPE PLUMBING
J 2
(-1075 2075);
DISPLAY 0.872340 (-1075 2075);
PAINT GREEN (-1075 2075);
DISPLAY INVISIBLE (-1075 2075);
FORCEPROP 1 LAST HDL_TAP TRUE
J 2
(-1400 1900);
DISPLAY 0.872340 (-1400 1900);
DISPLAY INVISIBLE (-1400 1900);
FORCEPROP 1 LAST PATH I53
J 2
(-1073 2025);
DISPLAY 0.872340 (-1073 2025);
PAINT GREEN (-1073 2025);
DISPLAY INVISIBLE (-1073 2025);
FORCEADD TAP..1
R 2
(-1075 2125);
FORCEPROP 3 LASTPIN (-1025 2125) SIG_NAME M_E_CPU1_SA_CB<2>
J 0
(-1015 2135);
DISPLAY 0.659574 (-1015 2135);
PAINT MONO (-1015 2135);
DISPLAY INVISIBLE (-1015 2135);
FORCEPROP 1 LASTPIN (-1025 2125) BN 2
J 2
(-1013 2133);
DISPLAY 0.680851 (-1013 2133);
PAINT GREEN (-1013 2133);
FORCEPROP 2 LAST CDS_LIB standard
J 0
(-1075 2125);
DISPLAY INVISIBLE (-1075 2125);
FORCEPROP 1 LAST BODY_TYPE PLUMBING
J 2
(-1075 2175);
DISPLAY 0.872340 (-1075 2175);
PAINT GREEN (-1075 2175);
DISPLAY INVISIBLE (-1075 2175);
FORCEPROP 1 LAST HDL_TAP TRUE
J 2
(-1400 2000);
DISPLAY 0.872340 (-1400 2000);
DISPLAY INVISIBLE (-1400 2000);
FORCEPROP 1 LAST PATH I54
J 2
(-1073 2125);
DISPLAY 0.872340 (-1073 2125);
PAINT GREEN (-1073 2125);
DISPLAY INVISIBLE (-1073 2125);
FORCEADD TAP..1
R 2
(-1075 2225);
FORCEPROP 3 LASTPIN (-1025 2225) SIG_NAME M_E_CPU1_SA_CB<4>
J 0
(-1015 2235);
DISPLAY 0.659574 (-1015 2235);
PAINT MONO (-1015 2235);
DISPLAY INVISIBLE (-1015 2235);
FORCEPROP 1 LASTPIN (-1025 2225) BN 4
J 2
(-1013 2233);
DISPLAY 0.680851 (-1013 2233);
PAINT GREEN (-1013 2233);
FORCEPROP 2 LAST CDS_LIB standard
J 0
(-1075 2225);
DISPLAY INVISIBLE (-1075 2225);
FORCEPROP 1 LAST BODY_TYPE PLUMBING
J 2
(-1075 2275);
DISPLAY 0.872340 (-1075 2275);
PAINT GREEN (-1075 2275);
DISPLAY INVISIBLE (-1075 2275);
FORCEPROP 1 LAST HDL_TAP TRUE
J 2
(-1400 2100);
DISPLAY 0.872340 (-1400 2100);
DISPLAY INVISIBLE (-1400 2100);
FORCEPROP 1 LAST PATH I55
J 2
(-1073 2225);
DISPLAY 0.872340 (-1073 2225);
PAINT GREEN (-1073 2225);
DISPLAY INVISIBLE (-1073 2225);
FORCEADD TAP..1
R 2
(-1075 2175);
FORCEPROP 3 LASTPIN (-1025 2175) SIG_NAME M_E_CPU1_SA_CB<3>
J 0
(-1015 2185);
DISPLAY 0.659574 (-1015 2185);
PAINT MONO (-1015 2185);
DISPLAY INVISIBLE (-1015 2185);
FORCEPROP 1 LASTPIN (-1025 2175) BN 3
J 2
(-1013 2183);
DISPLAY 0.680851 (-1013 2183);
PAINT GREEN (-1013 2183);
FORCEPROP 2 LAST CDS_LIB standard
J 0
(-1075 2175);
DISPLAY INVISIBLE (-1075 2175);
FORCEPROP 1 LAST BODY_TYPE PLUMBING
J 2
(-1075 2225);
DISPLAY 0.872340 (-1075 2225);
PAINT GREEN (-1075 2225);
DISPLAY INVISIBLE (-1075 2225);
FORCEPROP 1 LAST HDL_TAP TRUE
J 2
(-1400 2050);
DISPLAY 0.872340 (-1400 2050);
DISPLAY INVISIBLE (-1400 2050);
FORCEPROP 1 LAST PATH I56
J 2
(-1073 2175);
DISPLAY 0.872340 (-1073 2175);
PAINT GREEN (-1073 2175);
DISPLAY INVISIBLE (-1073 2175);
FORCEADD TAP..1
R 2
(-1075 2275);
FORCEPROP 3 LASTPIN (-1025 2275) SIG_NAME M_E_CPU1_SA_CB<5>
J 0
(-1015 2285);
DISPLAY 0.659574 (-1015 2285);
PAINT MONO (-1015 2285);
DISPLAY INVISIBLE (-1015 2285);
FORCEPROP 1 LASTPIN (-1025 2275) BN 5
J 2
(-1013 2283);
DISPLAY 0.680851 (-1013 2283);
PAINT GREEN (-1013 2283);
FORCEPROP 2 LAST CDS_LIB standard
J 0
(-1075 2275);
DISPLAY INVISIBLE (-1075 2275);
FORCEPROP 1 LAST BODY_TYPE PLUMBING
J 2
(-1075 2325);
DISPLAY 0.872340 (-1075 2325);
PAINT GREEN (-1075 2325);
DISPLAY INVISIBLE (-1075 2325);
FORCEPROP 1 LAST HDL_TAP TRUE
J 2
(-1400 2150);
DISPLAY 0.872340 (-1400 2150);
DISPLAY INVISIBLE (-1400 2150);
FORCEPROP 1 LAST PATH I57
J 2
(-1073 2275);
DISPLAY 0.872340 (-1073 2275);
PAINT GREEN (-1073 2275);
DISPLAY INVISIBLE (-1073 2275);
FORCEADD TAP..1
R 2
(-1075 2325);
FORCEPROP 3 LASTPIN (-1025 2325) SIG_NAME M_E_CPU1_SA_CB<6>
J 0
(-1015 2335);
DISPLAY 0.659574 (-1015 2335);
PAINT MONO (-1015 2335);
DISPLAY INVISIBLE (-1015 2335);
FORCEPROP 1 LASTPIN (-1025 2325) BN 6
J 2
(-1013 2333);
DISPLAY 0.680851 (-1013 2333);
PAINT GREEN (-1013 2333);
FORCEPROP 2 LAST CDS_LIB standard
J 0
(-1075 2325);
DISPLAY INVISIBLE (-1075 2325);
FORCEPROP 1 LAST BODY_TYPE PLUMBING
J 2
(-1075 2375);
DISPLAY 0.872340 (-1075 2375);
PAINT GREEN (-1075 2375);
DISPLAY INVISIBLE (-1075 2375);
FORCEPROP 1 LAST HDL_TAP TRUE
J 2
(-1400 2200);
DISPLAY 0.872340 (-1400 2200);
DISPLAY INVISIBLE (-1400 2200);
FORCEPROP 1 LAST PATH I58
J 2
(-1073 2325);
DISPLAY 0.872340 (-1073 2325);
PAINT GREEN (-1073 2325);
DISPLAY INVISIBLE (-1073 2325);
FORCEADD TAP..1
R 2
(-1075 2375);
FORCEPROP 3 LASTPIN (-1025 2375) SIG_NAME M_E_CPU1_SA_CB<7>
J 0
(-1015 2385);
DISPLAY 0.659574 (-1015 2385);
PAINT MONO (-1015 2385);
DISPLAY INVISIBLE (-1015 2385);
FORCEPROP 1 LASTPIN (-1025 2375) BN 7
J 2
(-1013 2383);
DISPLAY 0.680851 (-1013 2383);
PAINT GREEN (-1013 2383);
FORCEPROP 2 LAST CDS_LIB standard
J 0
(-1075 2375);
DISPLAY INVISIBLE (-1075 2375);
FORCEPROP 1 LAST BODY_TYPE PLUMBING
J 2
(-1075 2425);
DISPLAY 0.872340 (-1075 2425);
PAINT GREEN (-1075 2425);
DISPLAY INVISIBLE (-1075 2425);
FORCEPROP 1 LAST HDL_TAP TRUE
J 2
(-1400 2250);
DISPLAY 0.872340 (-1400 2250);
DISPLAY INVISIBLE (-1400 2250);
FORCEPROP 1 LAST PATH I59
J 2
(-1073 2375);
DISPLAY 0.872340 (-1073 2375);
PAINT GREEN (-1073 2375);
DISPLAY INVISIBLE (-1073 2375);
FORCEADD TAP..1
R 2
(-1075 -75);
FORCEPROP 3 LASTPIN (-1025 -75) SIG_NAME M_E_CPU1_CLK_DP<1>
J 0
(-1015 -65);
DISPLAY 0.659574 (-1015 -65);
PAINT MONO (-1015 -65);
DISPLAY INVISIBLE (-1015 -65);
FORCEPROP 1 LASTPIN (-1025 -75) BN 1
J 2
(-1013 -67);
DISPLAY 0.680851 (-1013 -67);
PAINT GREEN (-1013 -67);
FORCEPROP 2 LAST CDS_LIB standard
J 0
(-1075 -75);
DISPLAY INVISIBLE (-1075 -75);
FORCEPROP 1 LAST BODY_TYPE PLUMBING
J 2
(-1075 -25);
DISPLAY 0.872340 (-1075 -25);
PAINT GREEN (-1075 -25);
DISPLAY INVISIBLE (-1075 -25);
FORCEPROP 1 LAST HDL_TAP TRUE
J 2
(-1400 -200);
DISPLAY 0.872340 (-1400 -200);
DISPLAY INVISIBLE (-1400 -200);
FORCEPROP 1 LAST PATH I6
J 2
(-1073 -75);
DISPLAY 0.872340 (-1073 -75);
PAINT GREEN (-1073 -75);
DISPLAY INVISIBLE (-1073 -75);
FORCEADD TAP..1
R 2
(-1075 2425);
FORCEPROP 3 LASTPIN (-1025 2425) SIG_NAME M_E_CPU1_SA_DQ<0>
J 0
(-1015 2435);
DISPLAY 0.659574 (-1015 2435);
PAINT MONO (-1015 2435);
DISPLAY INVISIBLE (-1015 2435);
FORCEPROP 1 LASTPIN (-1025 2425) BN 0
J 2
(-1013 2433);
DISPLAY 0.680851 (-1013 2433);
PAINT GREEN (-1013 2433);
FORCEPROP 2 LAST CDS_LIB standard
J 0
(-1075 2425);
DISPLAY INVISIBLE (-1075 2425);
FORCEPROP 1 LAST BODY_TYPE PLUMBING
J 2
(-1075 2475);
DISPLAY 0.872340 (-1075 2475);
PAINT GREEN (-1075 2475);
DISPLAY INVISIBLE (-1075 2475);
FORCEPROP 1 LAST HDL_TAP TRUE
J 2
(-1400 2300);
DISPLAY 0.872340 (-1400 2300);
DISPLAY INVISIBLE (-1400 2300);
FORCEPROP 1 LAST PATH I60
J 2
(-1073 2425);
DISPLAY 0.872340 (-1073 2425);
PAINT GREEN (-1073 2425);
DISPLAY INVISIBLE (-1073 2425);
FORCEADD TAP..1
R 2
(-1075 2475);
FORCEPROP 3 LASTPIN (-1025 2475) SIG_NAME M_E_CPU1_SA_DQ<1>
J 0
(-1015 2485);
DISPLAY 0.659574 (-1015 2485);
PAINT MONO (-1015 2485);
DISPLAY INVISIBLE (-1015 2485);
FORCEPROP 1 LASTPIN (-1025 2475) BN 1
J 2
(-1013 2483);
DISPLAY 0.680851 (-1013 2483);
PAINT GREEN (-1013 2483);
FORCEPROP 2 LAST CDS_LIB standard
J 0
(-1075 2475);
DISPLAY INVISIBLE (-1075 2475);
FORCEPROP 1 LAST BODY_TYPE PLUMBING
J 2
(-1075 2525);
DISPLAY 0.872340 (-1075 2525);
PAINT GREEN (-1075 2525);
DISPLAY INVISIBLE (-1075 2525);
FORCEPROP 1 LAST HDL_TAP TRUE
J 2
(-1400 2350);
DISPLAY 0.872340 (-1400 2350);
DISPLAY INVISIBLE (-1400 2350);
FORCEPROP 1 LAST PATH I61
J 2
(-1073 2475);
DISPLAY 0.872340 (-1073 2475);
PAINT GREEN (-1073 2475);
DISPLAY INVISIBLE (-1073 2475);
FORCEADD TAP..1
R 2
(-1075 2525);
FORCEPROP 3 LASTPIN (-1025 2525) SIG_NAME M_E_CPU1_SA_DQ<2>
J 0
(-1015 2535);
DISPLAY 0.659574 (-1015 2535);
PAINT MONO (-1015 2535);
DISPLAY INVISIBLE (-1015 2535);
FORCEPROP 1 LASTPIN (-1025 2525) BN 2
J 2
(-1013 2533);
DISPLAY 0.680851 (-1013 2533);
PAINT GREEN (-1013 2533);
FORCEPROP 2 LAST CDS_LIB standard
J 0
(-1075 2525);
DISPLAY INVISIBLE (-1075 2525);
FORCEPROP 1 LAST BODY_TYPE PLUMBING
J 2
(-1075 2575);
DISPLAY 0.872340 (-1075 2575);
PAINT GREEN (-1075 2575);
DISPLAY INVISIBLE (-1075 2575);
FORCEPROP 1 LAST HDL_TAP TRUE
J 2
(-1400 2400);
DISPLAY 0.872340 (-1400 2400);
DISPLAY INVISIBLE (-1400 2400);
FORCEPROP 1 LAST PATH I62
J 2
(-1073 2525);
DISPLAY 0.872340 (-1073 2525);
PAINT GREEN (-1073 2525);
DISPLAY INVISIBLE (-1073 2525);
FORCEADD TAP..1
R 2
(-1075 2575);
FORCEPROP 3 LASTPIN (-1025 2575) SIG_NAME M_E_CPU1_SA_DQ<3>
J 0
(-1015 2585);
DISPLAY 0.659574 (-1015 2585);
PAINT MONO (-1015 2585);
DISPLAY INVISIBLE (-1015 2585);
FORCEPROP 1 LASTPIN (-1025 2575) BN 3
J 2
(-1013 2583);
DISPLAY 0.680851 (-1013 2583);
PAINT GREEN (-1013 2583);
FORCEPROP 2 LAST CDS_LIB standard
J 0
(-1075 2575);
DISPLAY INVISIBLE (-1075 2575);
FORCEPROP 1 LAST BODY_TYPE PLUMBING
J 2
(-1075 2625);
DISPLAY 0.872340 (-1075 2625);
PAINT GREEN (-1075 2625);
DISPLAY INVISIBLE (-1075 2625);
FORCEPROP 1 LAST HDL_TAP TRUE
J 2
(-1400 2450);
DISPLAY 0.872340 (-1400 2450);
DISPLAY INVISIBLE (-1400 2450);
FORCEPROP 1 LAST PATH I63
J 2
(-1073 2575);
DISPLAY 0.872340 (-1073 2575);
PAINT GREEN (-1073 2575);
DISPLAY INVISIBLE (-1073 2575);
FORCEADD TAP..1
R 2
(-1075 2625);
FORCEPROP 3 LASTPIN (-1025 2625) SIG_NAME M_E_CPU1_SA_DQ<4>
J 0
(-1015 2635);
DISPLAY 0.659574 (-1015 2635);
PAINT MONO (-1015 2635);
DISPLAY INVISIBLE (-1015 2635);
FORCEPROP 1 LASTPIN (-1025 2625) BN 4
J 2
(-1013 2633);
DISPLAY 0.680851 (-1013 2633);
PAINT GREEN (-1013 2633);
FORCEPROP 2 LAST CDS_LIB standard
J 0
(-1075 2625);
DISPLAY INVISIBLE (-1075 2625);
FORCEPROP 1 LAST BODY_TYPE PLUMBING
J 2
(-1075 2675);
DISPLAY 0.872340 (-1075 2675);
PAINT GREEN (-1075 2675);
DISPLAY INVISIBLE (-1075 2675);
FORCEPROP 1 LAST HDL_TAP TRUE
J 2
(-1400 2500);
DISPLAY 0.872340 (-1400 2500);
DISPLAY INVISIBLE (-1400 2500);
FORCEPROP 1 LAST PATH I64
J 2
(-1073 2625);
DISPLAY 0.872340 (-1073 2625);
PAINT GREEN (-1073 2625);
DISPLAY INVISIBLE (-1073 2625);
FORCEADD TAP..1
R 2
(-1075 2725);
FORCEPROP 3 LASTPIN (-1025 2725) SIG_NAME M_E_CPU1_SA_DQ<6>
J 0
(-1015 2735);
DISPLAY 0.659574 (-1015 2735);
PAINT MONO (-1015 2735);
DISPLAY INVISIBLE (-1015 2735);
FORCEPROP 1 LASTPIN (-1025 2725) BN 6
J 2
(-1013 2733);
DISPLAY 0.680851 (-1013 2733);
PAINT GREEN (-1013 2733);
FORCEPROP 2 LAST CDS_LIB standard
J 0
(-1075 2725);
DISPLAY INVISIBLE (-1075 2725);
FORCEPROP 1 LAST BODY_TYPE PLUMBING
J 2
(-1075 2775);
DISPLAY 0.872340 (-1075 2775);
PAINT GREEN (-1075 2775);
DISPLAY INVISIBLE (-1075 2775);
FORCEPROP 1 LAST HDL_TAP TRUE
J 2
(-1400 2600);
DISPLAY 0.872340 (-1400 2600);
DISPLAY INVISIBLE (-1400 2600);
FORCEPROP 1 LAST PATH I65
J 2
(-1073 2725);
DISPLAY 0.872340 (-1073 2725);
PAINT GREEN (-1073 2725);
DISPLAY INVISIBLE (-1073 2725);
FORCEADD TAP..1
R 2
(-1075 2675);
FORCEPROP 3 LASTPIN (-1025 2675) SIG_NAME M_E_CPU1_SA_DQ<5>
J 0
(-1015 2685);
DISPLAY 0.659574 (-1015 2685);
PAINT MONO (-1015 2685);
DISPLAY INVISIBLE (-1015 2685);
FORCEPROP 1 LASTPIN (-1025 2675) BN 5
J 2
(-1013 2683);
DISPLAY 0.680851 (-1013 2683);
PAINT GREEN (-1013 2683);
FORCEPROP 2 LAST CDS_LIB standard
J 0
(-1075 2675);
DISPLAY INVISIBLE (-1075 2675);
FORCEPROP 1 LAST BODY_TYPE PLUMBING
J 2
(-1075 2725);
DISPLAY 0.872340 (-1075 2725);
PAINT GREEN (-1075 2725);
DISPLAY INVISIBLE (-1075 2725);
FORCEPROP 1 LAST HDL_TAP TRUE
J 2
(-1400 2550);
DISPLAY 0.872340 (-1400 2550);
DISPLAY INVISIBLE (-1400 2550);
FORCEPROP 1 LAST PATH I66
J 2
(-1073 2675);
DISPLAY 0.872340 (-1073 2675);
PAINT GREEN (-1073 2675);
DISPLAY INVISIBLE (-1073 2675);
FORCEADD TAP..1
R 2
(-1075 2775);
FORCEPROP 3 LASTPIN (-1025 2775) SIG_NAME M_E_CPU1_SA_DQ<7>
J 0
(-1015 2785);
DISPLAY 0.659574 (-1015 2785);
PAINT MONO (-1015 2785);
DISPLAY INVISIBLE (-1015 2785);
FORCEPROP 1 LASTPIN (-1025 2775) BN 7
J 2
(-1013 2783);
DISPLAY 0.680851 (-1013 2783);
PAINT GREEN (-1013 2783);
FORCEPROP 2 LAST CDS_LIB standard
J 0
(-1075 2775);
DISPLAY INVISIBLE (-1075 2775);
FORCEPROP 1 LAST BODY_TYPE PLUMBING
J 2
(-1075 2825);
DISPLAY 0.872340 (-1075 2825);
PAINT GREEN (-1075 2825);
DISPLAY INVISIBLE (-1075 2825);
FORCEPROP 1 LAST HDL_TAP TRUE
J 2
(-1400 2650);
DISPLAY 0.872340 (-1400 2650);
DISPLAY INVISIBLE (-1400 2650);
FORCEPROP 1 LAST PATH I67
J 2
(-1073 2775);
DISPLAY 0.872340 (-1073 2775);
PAINT GREEN (-1073 2775);
DISPLAY INVISIBLE (-1073 2775);
FORCEADD TAP..1
R 2
(-1075 2825);
FORCEPROP 3 LASTPIN (-1025 2825) SIG_NAME M_E_CPU1_SA_DQ<8>
J 0
(-1015 2835);
DISPLAY 0.659574 (-1015 2835);
PAINT MONO (-1015 2835);
DISPLAY INVISIBLE (-1015 2835);
FORCEPROP 1 LASTPIN (-1025 2825) BN 8
J 2
(-1013 2833);
DISPLAY 0.680851 (-1013 2833);
PAINT GREEN (-1013 2833);
FORCEPROP 2 LAST CDS_LIB standard
J 0
(-1075 2825);
DISPLAY INVISIBLE (-1075 2825);
FORCEPROP 1 LAST BODY_TYPE PLUMBING
J 2
(-1075 2875);
DISPLAY 0.872340 (-1075 2875);
PAINT GREEN (-1075 2875);
DISPLAY INVISIBLE (-1075 2875);
FORCEPROP 1 LAST HDL_TAP TRUE
J 2
(-1400 2700);
DISPLAY 0.872340 (-1400 2700);
DISPLAY INVISIBLE (-1400 2700);
FORCEPROP 1 LAST PATH I68
J 2
(-1073 2825);
DISPLAY 0.872340 (-1073 2825);
PAINT GREEN (-1073 2825);
DISPLAY INVISIBLE (-1073 2825);
FORCEADD TAP..1
R 2
(-1075 2875);
FORCEPROP 3 LASTPIN (-1025 2875) SIG_NAME M_E_CPU1_SA_DQ<9>
J 0
(-1015 2885);
DISPLAY 0.659574 (-1015 2885);
PAINT MONO (-1015 2885);
DISPLAY INVISIBLE (-1015 2885);
FORCEPROP 1 LASTPIN (-1025 2875) BN 9
J 2
(-1013 2883);
DISPLAY 0.680851 (-1013 2883);
PAINT GREEN (-1013 2883);
FORCEPROP 2 LAST CDS_LIB standard
J 0
(-1075 2875);
DISPLAY INVISIBLE (-1075 2875);
FORCEPROP 1 LAST BODY_TYPE PLUMBING
J 2
(-1075 2925);
DISPLAY 0.872340 (-1075 2925);
PAINT GREEN (-1075 2925);
DISPLAY INVISIBLE (-1075 2925);
FORCEPROP 1 LAST HDL_TAP TRUE
J 2
(-1400 2750);
DISPLAY 0.872340 (-1400 2750);
DISPLAY INVISIBLE (-1400 2750);
FORCEPROP 1 LAST PATH I69
J 2
(-1073 2875);
DISPLAY 0.872340 (-1073 2875);
PAINT GREEN (-1073 2875);
DISPLAY INVISIBLE (-1073 2875);
FORCEADD SOCKET4677_AZIF0045P001C01CS..12
(650 1875);
FORCEPROP 1 LAST PART_NUMBER DGA^7000023
J 0
(-450 4225);
DISPLAY 0.723404 (-450 4225);
PAINT GREEN (-450 4225);
DISPLAY INVISIBLE (-450 4225);
FORCEPROP 2 LAST PART_TYPE SMLF
J 0
(-450 4400);
DISPLAY 1.021277 (-450 4400);
FORCEPROP 1 LAST MATERIAL IO
J 0
(-450 4150);
DISPLAY 0.723404 (-450 4150);
PAINT GREEN (-450 4150);
FORCEPROP 2 LAST VALUE SOCKET4677_AZIF0045-P001C01CS
J 0
(-450 4350);
DISPLAY 1.021277 (-450 4350);
FORCEPROP 1 LAST $LOCATION U1
J 0
(-450 4300);
DISPLAY 0.723404 (-450 4300);
PAINT GREEN (-450 4300);
FORCEPROP 0 LASTPIN (1875 25) $PN DD44
J 0
(1885 35);
DISPLAY 0.680851 (1885 35);
PAINT MONO (1885 35);
FORCEPROP 0 LASTPIN (1875 75) $PN DC43
J 0
(1885 85);
DISPLAY 0.680851 (1885 85);
PAINT MONO (1885 85);
FORCEPROP 0 LASTPIN (1875 -225) $PN CY47
J 0
(1885 -215);
DISPLAY 0.680851 (1885 -215);
PAINT MONO (1885 -215);
FORCEPROP 0 LASTPIN (1875 -125) $PN DF44
J 0
(1885 -115);
DISPLAY 0.680851 (1885 -115);
PAINT MONO (1885 -115);
FORCEPROP 0 LASTPIN (1875 -75) $PN DG43
J 0
(1885 -65);
DISPLAY 0.680851 (1885 -65);
PAINT MONO (1885 -65);
FORCEPROP 0 LASTPIN (-575 -225) $PN EJ45
J 2
(-585 -215);
DISPLAY 0.680851 (-585 -215);
PAINT MONO (-585 -215);
FORCEPROP 0 LASTPIN (-575 -175) $PN EE45
J 2
(-585 -165);
DISPLAY 0.680851 (-585 -165);
PAINT MONO (-585 -165);
FORCEPROP 0 LASTPIN (-575 -125) $PN EG45
J 2
(-585 -115);
DISPLAY 0.680851 (-585 -115);
PAINT MONO (-585 -115);
FORCEPROP 0 LASTPIN (-575 -75) $PN EC45
J 2
(-585 -65);
DISPLAY 0.680851 (-585 -65);
PAINT MONO (-585 -65);
FORCEPROP 0 LASTPIN (1875 1375) $PN EP49
J 0
(1885 1385);
DISPLAY 0.680851 (1885 1385);
PAINT MONO (1885 1385);
FORCEPROP 0 LASTPIN (1875 1425) $PN ET49
J 0
(1885 1435);
DISPLAY 0.680851 (1885 1435);
PAINT MONO (1885 1435);
FORCEPROP 0 LASTPIN (1875 1475) $PN EK49
J 0
(1885 1485);
DISPLAY 0.680851 (1885 1485);
PAINT MONO (1885 1485);
FORCEPROP 0 LASTPIN (1875 1525) $PN EL48
J 0
(1885 1535);
DISPLAY 0.680851 (1885 1535);
PAINT MONO (1885 1535);
FORCEPROP 0 LASTPIN (1875 1575) $PN EM47
J 0
(1885 1585);
DISPLAY 0.680851 (1885 1585);
PAINT MONO (1885 1585);
FORCEPROP 0 LASTPIN (1875 1625) $PN EP47
J 0
(1885 1635);
DISPLAY 0.680851 (1885 1635);
PAINT MONO (1885 1635);
FORCEPROP 0 LASTPIN (1875 1675) $PN ED44
J 0
(1885 1685);
DISPLAY 0.680851 (1885 1685);
PAINT MONO (1885 1685);
FORCEPROP 0 LASTPIN (-575 2425) $PN EL78
J 2
(-585 2435);
DISPLAY 0.680851 (-585 2435);
PAINT MONO (-585 2435);
FORCEPROP 0 LASTPIN (-575 2475) $PN EM77
J 2
(-585 2485);
DISPLAY 0.680851 (-585 2485);
PAINT MONO (-585 2485);
FORCEPROP 0 LASTPIN (-575 2525) $PN EP79
J 2
(-585 2535);
DISPLAY 0.680851 (-585 2535);
PAINT MONO (-585 2535);
FORCEPROP 0 LASTPIN (-575 2575) $PN ER76
J 2
(-585 2585);
DISPLAY 0.680851 (-585 2585);
PAINT MONO (-585 2585);
FORCEPROP 0 LASTPIN (-575 2625) $PN EL74
J 2
(-585 2635);
DISPLAY 0.680851 (-585 2635);
PAINT MONO (-585 2635);
FORCEPROP 0 LASTPIN (-575 2675) $PN EK73
J 2
(-585 2685);
DISPLAY 0.680851 (-585 2685);
PAINT MONO (-585 2685);
FORCEPROP 0 LASTPIN (-575 2725) $PN EP73
J 2
(-585 2735);
DISPLAY 0.680851 (-585 2735);
PAINT MONO (-585 2735);
FORCEPROP 0 LASTPIN (-575 2775) $PN ER72
J 2
(-585 2785);
DISPLAY 0.680851 (-585 2785);
PAINT MONO (-585 2785);
FORCEPROP 0 LASTPIN (-575 2825) $PN EE72
J 2
(-585 2835);
DISPLAY 0.680851 (-585 2835);
PAINT MONO (-585 2835);
FORCEPROP 0 LASTPIN (-575 2875) $PN ED71
J 2
(-585 2885);
DISPLAY 0.680851 (-585 2885);
PAINT MONO (-585 2885);
FORCEPROP 0 LASTPIN (-575 2925) $PN EG72
J 2
(-585 2935);
DISPLAY 0.680851 (-585 2935);
PAINT MONO (-585 2935);
FORCEPROP 0 LASTPIN (-575 2975) $PN EH71
J 2
(-585 2985);
DISPLAY 0.680851 (-585 2985);
PAINT MONO (-585 2985);
FORCEPROP 0 LASTPIN (-575 3025) $PN ED69
J 2
(-585 3035);
DISPLAY 0.680851 (-585 3035);
PAINT MONO (-585 3035);
FORCEPROP 0 LASTPIN (-575 3075) $PN EE68
J 2
(-585 3085);
DISPLAY 0.680851 (-585 3085);
PAINT MONO (-585 3085);
FORCEPROP 0 LASTPIN (-575 3125) $PN EH69
J 2
(-585 3135);
DISPLAY 0.680851 (-585 3135);
PAINT MONO (-585 3135);
FORCEPROP 0 LASTPIN (-575 3175) $PN EG68
J 2
(-585 3185);
DISPLAY 0.680851 (-585 3185);
PAINT MONO (-585 3185);
FORCEPROP 0 LASTPIN (-575 3225) $PN EM71
J 2
(-585 3235);
DISPLAY 0.680851 (-585 3235);
PAINT MONO (-585 3235);
FORCEPROP 0 LASTPIN (-575 3275) $PN EM69
J 2
(-585 3285);
DISPLAY 0.680851 (-585 3285);
PAINT MONO (-585 3285);
FORCEPROP 0 LASTPIN (-575 3325) $PN EN70
J 2
(-585 3335);
DISPLAY 0.680851 (-585 3335);
PAINT MONO (-585 3335);
FORCEPROP 0 LASTPIN (-575 3375) $PN ER68
J 2
(-585 3385);
DISPLAY 0.680851 (-585 3385);
PAINT MONO (-585 3385);
FORCEPROP 0 LASTPIN (-575 3425) $PN ER66
J 2
(-585 3435);
DISPLAY 0.680851 (-585 3435);
PAINT MONO (-585 3435);
FORCEPROP 0 LASTPIN (-575 3475) $PN EM65
J 2
(-585 3485);
DISPLAY 0.680851 (-585 3485);
PAINT MONO (-585 3485);
FORCEPROP 0 LASTPIN (-575 3525) $PN EL66
J 2
(-585 3535);
DISPLAY 0.680851 (-585 3535);
PAINT MONO (-585 3535);
FORCEPROP 0 LASTPIN (-575 3575) $PN EP65
J 2
(-585 3585);
DISPLAY 0.680851 (-585 3585);
PAINT MONO (-585 3585);
FORCEPROP 0 LASTPIN (-575 3625) $PN EM63
J 2
(-585 3635);
DISPLAY 0.680851 (-585 3635);
PAINT MONO (-585 3635);
FORCEPROP 0 LASTPIN (-575 3675) $PN EL62
J 2
(-585 3685);
DISPLAY 0.680851 (-585 3685);
PAINT MONO (-585 3685);
FORCEPROP 0 LASTPIN (-575 3725) $PN EP63
J 2
(-585 3735);
DISPLAY 0.680851 (-585 3735);
PAINT MONO (-585 3735);
FORCEPROP 0 LASTPIN (-575 3775) $PN ER62
J 2
(-585 3785);
DISPLAY 0.680851 (-585 3785);
PAINT MONO (-585 3785);
FORCEPROP 0 LASTPIN (-575 3825) $PN EL60
J 2
(-585 3835);
DISPLAY 0.680851 (-585 3835);
PAINT MONO (-585 3835);
FORCEPROP 0 LASTPIN (-575 3875) $PN EM59
J 2
(-585 3885);
DISPLAY 0.680851 (-585 3885);
PAINT MONO (-585 3885);
FORCEPROP 0 LASTPIN (-575 3925) $PN ER60
J 2
(-585 3935);
DISPLAY 0.680851 (-585 3935);
PAINT MONO (-585 3935);
FORCEPROP 0 LASTPIN (-575 3975) $PN EP59
J 2
(-585 3985);
DISPLAY 0.680851 (-585 3985);
PAINT MONO (-585 3985);
FORCEPROP 0 LASTPIN (1875 2975) $PN EP75
J 0
(1885 2985);
DISPLAY 0.680851 (1885 2985);
PAINT MONO (1885 2985);
FORCEPROP 0 LASTPIN (1875 3025) $PN EC70
J 0
(1885 3035);
DISPLAY 0.680851 (1885 3035);
PAINT MONO (1885 3035);
FORCEPROP 0 LASTPIN (1875 3075) $PN EK67
J 0
(1885 3085);
DISPLAY 0.680851 (1885 3085);
PAINT MONO (1885 3085);
FORCEPROP 0 LASTPIN (1875 3125) $PN EK61
J 0
(1885 3135);
DISPLAY 0.680851 (1885 3135);
PAINT MONO (1885 3135);
FORCEPROP 0 LASTPIN (1875 3175) $PN EM55
J 0
(1885 3185);
DISPLAY 0.680851 (1885 3185);
PAINT MONO (1885 3185);
FORCEPROP 0 LASTPIN (1875 3225) $PN EM75
J 0
(1885 3235);
DISPLAY 0.680851 (1885 3235);
PAINT MONO (1885 3235);
FORCEPROP 0 LASTPIN (1875 3275) $PN EJ70
J 0
(1885 3285);
DISPLAY 0.680851 (1885 3285);
PAINT MONO (1885 3285);
FORCEPROP 0 LASTPIN (1875 3325) $PN EN68
J 0
(1885 3335);
DISPLAY 0.680851 (1885 3335);
PAINT MONO (1885 3335);
FORCEPROP 0 LASTPIN (1875 3375) $PN ET61
J 0
(1885 3385);
DISPLAY 0.680851 (1885 3385);
PAINT MONO (1885 3385);
FORCEPROP 0 LASTPIN (1875 3425) $PN ET55
J 0
(1885 3435);
DISPLAY 0.680851 (1885 3435);
PAINT MONO (1885 3435);
FORCEPROP 0 LASTPIN (1875 3525) $PN EN76
J 0
(1885 3535);
DISPLAY 0.680851 (1885 3535);
PAINT MONO (1885 3535);
FORCEPROP 0 LASTPIN (1875 3575) $PN EE70
J 0
(1885 3585);
DISPLAY 0.680851 (1885 3585);
PAINT MONO (1885 3585);
FORCEPROP 0 LASTPIN (1875 3625) $PN EL68
J 0
(1885 3635);
DISPLAY 0.680851 (1885 3635);
PAINT MONO (1885 3635);
FORCEPROP 0 LASTPIN (1875 3675) $PN EM61
J 0
(1885 3685);
DISPLAY 0.680851 (1885 3685);
PAINT MONO (1885 3685);
FORCEPROP 0 LASTPIN (1875 3725) $PN EK55
J 0
(1885 3735);
DISPLAY 0.680851 (1885 3735);
PAINT MONO (1885 3735);
FORCEPROP 0 LASTPIN (1875 3775) $PN EN74
J 0
(1885 3785);
DISPLAY 0.680851 (1885 3785);
PAINT MONO (1885 3785);
FORCEPROP 0 LASTPIN (1875 3825) $PN EG70
J 0
(1885 3835);
DISPLAY 0.680851 (1885 3835);
PAINT MONO (1885 3835);
FORCEPROP 0 LASTPIN (1875 3875) $PN EM67
J 0
(1885 3885);
DISPLAY 0.680851 (1885 3885);
PAINT MONO (1885 3885);
FORCEPROP 0 LASTPIN (1875 3925) $PN EP61
J 0
(1885 3935);
DISPLAY 0.680851 (1885 3935);
PAINT MONO (1885 3935);
FORCEPROP 0 LASTPIN (1875 3975) $PN EP55
J 0
(1885 3985);
DISPLAY 0.680851 (1885 3985);
PAINT MONO (1885 3985);
FORCEPROP 0 LASTPIN (-575 2025) $PN EM57
J 2
(-585 2035);
DISPLAY 0.680851 (-585 2035);
PAINT MONO (-585 2035);
FORCEPROP 0 LASTPIN (-575 2075) $PN EL56
J 2
(-585 2085);
DISPLAY 0.680851 (-585 2085);
PAINT MONO (-585 2085);
FORCEPROP 0 LASTPIN (-575 2125) $PN EP57
J 2
(-585 2135);
DISPLAY 0.680851 (-585 2135);
PAINT MONO (-585 2135);
FORCEPROP 0 LASTPIN (-575 2175) $PN ER56
J 2
(-585 2185);
DISPLAY 0.680851 (-585 2185);
PAINT MONO (-585 2185);
FORCEPROP 0 LASTPIN (-575 2225) $PN EL54
J 2
(-585 2235);
DISPLAY 0.680851 (-585 2235);
PAINT MONO (-585 2235);
FORCEPROP 0 LASTPIN (-575 2275) $PN EM53
J 2
(-585 2285);
DISPLAY 0.680851 (-585 2285);
PAINT MONO (-585 2285);
FORCEPROP 0 LASTPIN (-575 2325) $PN ER54
J 2
(-585 2335);
DISPLAY 0.680851 (-585 2335);
PAINT MONO (-585 2335);
FORCEPROP 0 LASTPIN (-575 2375) $PN EP53
J 2
(-585 2385);
DISPLAY 0.680851 (-585 2385);
PAINT MONO (-585 2385);
FORCEPROP 0 LASTPIN (1875 1325) $PN EE43
J 0
(1885 1335);
DISPLAY 0.680851 (1885 1335);
PAINT MONO (1885 1335);
FORCEPROP 0 LASTPIN (1875 875) $PN EG43
J 0
(1885 885);
DISPLAY 0.680851 (1885 885);
PAINT MONO (1885 885);
FORCEPROP 0 LASTPIN (1875 925) $PN EH44
J 0
(1885 935);
DISPLAY 0.680851 (1885 935);
PAINT MONO (1885 935);
FORCEPROP 0 LASTPIN (1875 975) $PN EM44
J 0
(1885 985);
DISPLAY 0.680851 (1885 985);
PAINT MONO (1885 985);
FORCEPROP 0 LASTPIN (1875 1025) $PN EP44
J 0
(1885 1035);
DISPLAY 0.680851 (1885 1035);
PAINT MONO (1885 1035);
FORCEPROP 0 LASTPIN (1875 1075) $PN EL43
J 0
(1885 1085);
DISPLAY 0.680851 (1885 1085);
PAINT MONO (1885 1085);
FORCEPROP 0 LASTPIN (1875 1125) $PN ET42
J 0
(1885 1135);
DISPLAY 0.680851 (1885 1135);
PAINT MONO (1885 1135);
FORCEPROP 0 LASTPIN (1875 1175) $PN EK42
J 0
(1885 1185);
DISPLAY 0.680851 (1885 1185);
PAINT MONO (1885 1185);
FORCEPROP 0 LASTPIN (-575 425) $PN EE29
J 2
(-585 435);
DISPLAY 0.680851 (-585 435);
PAINT MONO (-585 435);
FORCEPROP 0 LASTPIN (-575 475) $PN ED28
J 2
(-585 485);
DISPLAY 0.680851 (-585 485);
PAINT MONO (-585 485);
FORCEPROP 0 LASTPIN (-575 525) $PN EG29
J 2
(-585 535);
DISPLAY 0.680851 (-585 535);
PAINT MONO (-585 535);
FORCEPROP 0 LASTPIN (-575 575) $PN EH28
J 2
(-585 585);
DISPLAY 0.680851 (-585 585);
PAINT MONO (-585 585);
FORCEPROP 0 LASTPIN (-575 625) $PN ED26
J 2
(-585 635);
DISPLAY 0.680851 (-585 635);
PAINT MONO (-585 635);
FORCEPROP 0 LASTPIN (-575 675) $PN EE25
J 2
(-585 685);
DISPLAY 0.680851 (-585 685);
PAINT MONO (-585 685);
FORCEPROP 0 LASTPIN (-575 725) $PN EH26
J 2
(-585 735);
DISPLAY 0.680851 (-585 735);
PAINT MONO (-585 735);
FORCEPROP 0 LASTPIN (-575 775) $PN EG25
J 2
(-585 785);
DISPLAY 0.680851 (-585 785);
PAINT MONO (-585 785);
FORCEPROP 0 LASTPIN (-575 825) $PN EM32
J 2
(-585 835);
DISPLAY 0.680851 (-585 835);
PAINT MONO (-585 835);
FORCEPROP 0 LASTPIN (-575 875) $PN EL31
J 2
(-585 885);
DISPLAY 0.680851 (-585 885);
PAINT MONO (-585 885);
FORCEPROP 0 LASTPIN (-575 925) $PN EP32
J 2
(-585 935);
DISPLAY 0.680851 (-585 935);
PAINT MONO (-585 935);
FORCEPROP 0 LASTPIN (-575 975) $PN ER31
J 2
(-585 985);
DISPLAY 0.680851 (-585 985);
PAINT MONO (-585 985);
FORCEPROP 0 LASTPIN (-575 1025) $PN EL29
J 2
(-585 1035);
DISPLAY 0.680851 (-585 1035);
PAINT MONO (-585 1035);
FORCEPROP 0 LASTPIN (-575 1075) $PN EM28
J 2
(-585 1085);
DISPLAY 0.680851 (-585 1085);
PAINT MONO (-585 1085);
FORCEPROP 0 LASTPIN (-575 1125) $PN ER29
J 2
(-585 1135);
DISPLAY 0.680851 (-585 1135);
PAINT MONO (-585 1135);
FORCEPROP 0 LASTPIN (-575 1175) $PN EP28
J 2
(-585 1185);
DISPLAY 0.680851 (-585 1185);
PAINT MONO (-585 1185);
FORCEPROP 0 LASTPIN (-575 1225) $PN EM26
J 2
(-585 1235);
DISPLAY 0.680851 (-585 1235);
PAINT MONO (-585 1235);
FORCEPROP 0 LASTPIN (-575 1275) $PN EL25
J 2
(-585 1285);
DISPLAY 0.680851 (-585 1285);
PAINT MONO (-585 1285);
FORCEPROP 0 LASTPIN (-575 1325) $PN EP26
J 2
(-585 1335);
DISPLAY 0.680851 (-585 1335);
PAINT MONO (-585 1335);
FORCEPROP 0 LASTPIN (-575 1375) $PN ER25
J 2
(-585 1385);
DISPLAY 0.680851 (-585 1385);
PAINT MONO (-585 1385);
FORCEPROP 0 LASTPIN (-575 1425) $PN EL23
J 2
(-585 1435);
DISPLAY 0.680851 (-585 1435);
PAINT MONO (-585 1435);
FORCEPROP 0 LASTPIN (-575 1475) $PN EM22
J 2
(-585 1485);
DISPLAY 0.680851 (-585 1485);
PAINT MONO (-585 1485);
FORCEPROP 0 LASTPIN (-575 1525) $PN ER23
J 2
(-585 1535);
DISPLAY 0.680851 (-585 1535);
PAINT MONO (-585 1535);
FORCEPROP 0 LASTPIN (-575 1575) $PN EP22
J 2
(-585 1585);
DISPLAY 0.680851 (-585 1585);
PAINT MONO (-585 1585);
FORCEPROP 0 LASTPIN (-575 1625) $PN EM20
J 2
(-585 1635);
DISPLAY 0.680851 (-585 1635);
PAINT MONO (-585 1635);
FORCEPROP 0 LASTPIN (-575 1675) $PN EL19
J 2
(-585 1685);
DISPLAY 0.680851 (-585 1685);
PAINT MONO (-585 1685);
FORCEPROP 0 LASTPIN (-575 1725) $PN EP20
J 2
(-585 1735);
DISPLAY 0.680851 (-585 1735);
PAINT MONO (-585 1735);
FORCEPROP 0 LASTPIN (-575 1775) $PN ER19
J 2
(-585 1785);
DISPLAY 0.680851 (-585 1785);
PAINT MONO (-585 1785);
FORCEPROP 0 LASTPIN (-575 1825) $PN EL17
J 2
(-585 1835);
DISPLAY 0.680851 (-585 1835);
PAINT MONO (-585 1835);
FORCEPROP 0 LASTPIN (-575 1875) $PN EM16
J 2
(-585 1885);
DISPLAY 0.680851 (-585 1885);
PAINT MONO (-585 1885);
FORCEPROP 0 LASTPIN (-575 1925) $PN ER17
J 2
(-585 1935);
DISPLAY 0.680851 (-585 1935);
PAINT MONO (-585 1935);
FORCEPROP 0 LASTPIN (-575 1975) $PN EP16
J 2
(-585 1985);
DISPLAY 0.680851 (-585 1985);
PAINT MONO (-585 1985);
FORCEPROP 0 LASTPIN (1875 1825) $PN EE27
J 0
(1885 1835);
DISPLAY 0.680851 (1885 1835);
PAINT MONO (1885 1835);
FORCEPROP 0 LASTPIN (1875 1875) $PN EK30
J 0
(1885 1885);
DISPLAY 0.680851 (1885 1885);
PAINT MONO (1885 1885);
FORCEPROP 0 LASTPIN (1875 1925) $PN EK24
J 0
(1885 1935);
DISPLAY 0.680851 (1885 1935);
PAINT MONO (1885 1935);
FORCEPROP 0 LASTPIN (1875 1975) $PN EK18
J 0
(1885 1985);
DISPLAY 0.680851 (1885 1985);
PAINT MONO (1885 1985);
FORCEPROP 0 LASTPIN (1875 2025) $PN ET36
J 0
(1885 2035);
DISPLAY 0.680851 (1885 2035);
PAINT MONO (1885 2035);
FORCEPROP 0 LASTPIN (1875 2075) $PN EJ27
J 0
(1885 2085);
DISPLAY 0.680851 (1885 2085);
PAINT MONO (1885 2085);
FORCEPROP 0 LASTPIN (1875 2125) $PN ET30
J 0
(1885 2135);
DISPLAY 0.680851 (1885 2135);
PAINT MONO (1885 2135);
FORCEPROP 0 LASTPIN (1875 2175) $PN ET24
J 0
(1885 2185);
DISPLAY 0.680851 (1885 2185);
PAINT MONO (1885 2185);
FORCEPROP 0 LASTPIN (1875 2225) $PN ET18
J 0
(1885 2235);
DISPLAY 0.680851 (1885 2235);
PAINT MONO (1885 2235);
FORCEPROP 0 LASTPIN (1875 2275) $PN EK36
J 0
(1885 2285);
DISPLAY 0.680851 (1885 2285);
PAINT MONO (1885 2285);
FORCEPROP 0 LASTPIN (1875 2375) $PN EC27
J 0
(1885 2385);
DISPLAY 0.680851 (1885 2385);
PAINT MONO (1885 2385);
FORCEPROP 0 LASTPIN (1875 2425) $PN EM30
J 0
(1885 2435);
DISPLAY 0.680851 (1885 2435);
PAINT MONO (1885 2435);
FORCEPROP 0 LASTPIN (1875 2475) $PN EM24
J 0
(1885 2485);
DISPLAY 0.680851 (1885 2485);
PAINT MONO (1885 2485);
FORCEPROP 0 LASTPIN (1875 2525) $PN EM18
J 0
(1885 2535);
DISPLAY 0.680851 (1885 2535);
PAINT MONO (1885 2535);
FORCEPROP 0 LASTPIN (1875 2575) $PN EP36
J 0
(1885 2585);
DISPLAY 0.680851 (1885 2585);
PAINT MONO (1885 2585);
FORCEPROP 0 LASTPIN (1875 2625) $PN EG27
J 0
(1885 2635);
DISPLAY 0.680851 (1885 2635);
PAINT MONO (1885 2635);
FORCEPROP 0 LASTPIN (1875 2675) $PN EP30
J 0
(1885 2685);
DISPLAY 0.680851 (1885 2685);
PAINT MONO (1885 2685);
FORCEPROP 0 LASTPIN (1875 2725) $PN EP24
J 0
(1885 2735);
DISPLAY 0.680851 (1885 2735);
PAINT MONO (1885 2735);
FORCEPROP 0 LASTPIN (1875 2775) $PN EP18
J 0
(1885 2785);
DISPLAY 0.680851 (1885 2785);
PAINT MONO (1885 2785);
FORCEPROP 0 LASTPIN (1875 2825) $PN EM36
J 0
(1885 2835);
DISPLAY 0.680851 (1885 2835);
PAINT MONO (1885 2835);
FORCEPROP 0 LASTPIN (-575 25) $PN EL35
J 2
(-585 35);
DISPLAY 0.680851 (-585 35);
PAINT MONO (-585 35);
FORCEPROP 0 LASTPIN (-575 75) $PN EM34
J 2
(-585 85);
DISPLAY 0.680851 (-585 85);
PAINT MONO (-585 85);
FORCEPROP 0 LASTPIN (-575 125) $PN ER35
J 2
(-585 135);
DISPLAY 0.680851 (-585 135);
PAINT MONO (-585 135);
FORCEPROP 0 LASTPIN (-575 175) $PN EP34
J 2
(-585 185);
DISPLAY 0.680851 (-585 185);
PAINT MONO (-585 185);
FORCEPROP 0 LASTPIN (-575 225) $PN EM38
J 2
(-585 235);
DISPLAY 0.680851 (-585 235);
PAINT MONO (-585 235);
FORCEPROP 0 LASTPIN (-575 275) $PN EL37
J 2
(-585 285);
DISPLAY 0.680851 (-585 285);
PAINT MONO (-585 285);
FORCEPROP 0 LASTPIN (-575 325) $PN EP38
J 2
(-585 335);
DISPLAY 0.680851 (-585 335);
PAINT MONO (-585 335);
FORCEPROP 0 LASTPIN (-575 375) $PN ER37
J 2
(-585 385);
DISPLAY 0.680851 (-585 385);
PAINT MONO (-585 385);
FORCEPROP 0 LASTPIN (1875 825) $PN EP42
J 0
(1885 835);
DISPLAY 0.680851 (1885 835);
PAINT MONO (1885 835);
FORCEPROP 0 LASTPIN (1875 525) $PN EP51
J 0
(1885 535);
DISPLAY 0.680851 (1885 535);
PAINT MONO (1885 535);
FORCEPROP 0 LASTPIN (1875 575) $PN ET51
J 0
(1885 585);
DISPLAY 0.680851 (1885 585);
PAINT MONO (1885 585);
FORCEPROP 0 LASTPIN (1875 625) $PN EM51
J 0
(1885 635);
DISPLAY 0.680851 (1885 635);
PAINT MONO (1885 635);
FORCEPROP 0 LASTPIN (1875 675) $PN EL50
J 0
(1885 685);
DISPLAY 0.680851 (1885 685);
PAINT MONO (1885 685);
FORCEPROP 0 LASTPIN (1875 225) $PN EP40
J 0
(1885 235);
DISPLAY 0.680851 (1885 235);
PAINT MONO (1885 235);
FORCEPROP 0 LASTPIN (1875 275) $PN ET40
J 0
(1885 285);
DISPLAY 0.680851 (1885 285);
PAINT MONO (1885 285);
FORCEPROP 0 LASTPIN (1875 325) $PN EM40
J 0
(1885 335);
DISPLAY 0.680851 (1885 335);
PAINT MONO (1885 335);
FORCEPROP 0 LASTPIN (1875 375) $PN EL41
J 0
(1885 385);
DISPLAY 0.680851 (1885 385);
PAINT MONO (1885 385);
FORCEPROP 2 LAST CDS_LIB pure_quanta
J 0
(650 1875);
DISPLAY INVISIBLE (650 1875);
FORCEPROP 1 LAST NEEDS_NO_SIZE TRUE
J 0
(650 1875);
DISPLAY 0.723404 (650 1875);
PAINT GREEN (650 1875);
DISPLAY INVISIBLE (650 1875);
FORCEPROP 1 LAST CDS_LMAN_SYM_OUTLINE -1100,2250,1050,-2250
J 0
(650 1875);
DISPLAY 0.468085 (650 1875);
PAINT GREEN (650 1875);
DISPLAY INVISIBLE (650 1875);
FORCEPROP 2 LAST CDS_LOCATION U1
J 0
(-450 4450);
DISPLAY 1.021277 (-450 4450);
DISPLAY INVISIBLE (-450 4450);
FORCEPROP 0 LAST $SEC 12
J 0
(-450 4450);
DISPLAY 0.680851 (-450 4450);
PAINT MONO (-450 4450);
DISPLAY INVISIBLE (-450 4450);
FORCEPROP 2 LAST CDS_SEC 12
J 0
(-450 4450);
DISPLAY 1.021277 (-450 4450);
DISPLAY INVISIBLE (-450 4450);
FORCEPROP 1 LAST PATH I7
J 0
(650 1875);
DISPLAY 0.723404 (650 1875);
PAINT GREEN (650 1875);
DISPLAY INVISIBLE (650 1875);
FORCEADD TAP..1
R 2
(-1075 2975);
FORCEPROP 3 LASTPIN (-1025 2975) SIG_NAME M_E_CPU1_SA_DQ<11>
J 0
(-1015 2985);
DISPLAY 0.659574 (-1015 2985);
PAINT MONO (-1015 2985);
DISPLAY INVISIBLE (-1015 2985);
FORCEPROP 1 LASTPIN (-1025 2975) BN 11
J 2
(-1013 2983);
DISPLAY 0.680851 (-1013 2983);
PAINT GREEN (-1013 2983);
FORCEPROP 2 LAST CDS_LIB standard
J 0
(-1075 2975);
DISPLAY INVISIBLE (-1075 2975);
FORCEPROP 1 LAST BODY_TYPE PLUMBING
J 2
(-1075 3025);
DISPLAY 0.872340 (-1075 3025);
PAINT GREEN (-1075 3025);
DISPLAY INVISIBLE (-1075 3025);
FORCEPROP 1 LAST HDL_TAP TRUE
J 2
(-1400 2850);
DISPLAY 0.872340 (-1400 2850);
DISPLAY INVISIBLE (-1400 2850);
FORCEPROP 1 LAST PATH I70
J 2
(-1073 2975);
DISPLAY 0.872340 (-1073 2975);
PAINT GREEN (-1073 2975);
DISPLAY INVISIBLE (-1073 2975);
FORCEADD TAP..1
R 2
(-1075 2925);
FORCEPROP 3 LASTPIN (-1025 2925) SIG_NAME M_E_CPU1_SA_DQ<10>
J 0
(-1015 2935);
DISPLAY 0.659574 (-1015 2935);
PAINT MONO (-1015 2935);
DISPLAY INVISIBLE (-1015 2935);
FORCEPROP 1 LASTPIN (-1025 2925) BN 10
J 2
(-1013 2933);
DISPLAY 0.680851 (-1013 2933);
PAINT GREEN (-1013 2933);
FORCEPROP 2 LAST CDS_LIB standard
J 0
(-1075 2925);
DISPLAY INVISIBLE (-1075 2925);
FORCEPROP 1 LAST BODY_TYPE PLUMBING
J 2
(-1075 2975);
DISPLAY 0.872340 (-1075 2975);
PAINT GREEN (-1075 2975);
DISPLAY INVISIBLE (-1075 2975);
FORCEPROP 1 LAST HDL_TAP TRUE
J 2
(-1400 2800);
DISPLAY 0.872340 (-1400 2800);
DISPLAY INVISIBLE (-1400 2800);
FORCEPROP 1 LAST PATH I71
J 2
(-1073 2925);
DISPLAY 0.872340 (-1073 2925);
PAINT GREEN (-1073 2925);
DISPLAY INVISIBLE (-1073 2925);
FORCEADD TAP..1
R 2
(-1075 3025);
FORCEPROP 3 LASTPIN (-1025 3025) SIG_NAME M_E_CPU1_SA_DQ<12>
J 0
(-1015 3035);
DISPLAY 0.659574 (-1015 3035);
PAINT MONO (-1015 3035);
DISPLAY INVISIBLE (-1015 3035);
FORCEPROP 1 LASTPIN (-1025 3025) BN 12
J 2
(-1013 3033);
DISPLAY 0.680851 (-1013 3033);
PAINT GREEN (-1013 3033);
FORCEPROP 2 LAST CDS_LIB standard
J 0
(-1075 3025);
DISPLAY INVISIBLE (-1075 3025);
FORCEPROP 1 LAST BODY_TYPE PLUMBING
J 2
(-1075 3075);
DISPLAY 0.872340 (-1075 3075);
PAINT GREEN (-1075 3075);
DISPLAY INVISIBLE (-1075 3075);
FORCEPROP 1 LAST HDL_TAP TRUE
J 2
(-1400 2900);
DISPLAY 0.872340 (-1400 2900);
DISPLAY INVISIBLE (-1400 2900);
FORCEPROP 1 LAST PATH I72
J 2
(-1073 3025);
DISPLAY 0.872340 (-1073 3025);
PAINT GREEN (-1073 3025);
DISPLAY INVISIBLE (-1073 3025);
FORCEADD TAP..1
R 2
(-1075 3075);
FORCEPROP 3 LASTPIN (-1025 3075) SIG_NAME M_E_CPU1_SA_DQ<13>
J 0
(-1015 3085);
DISPLAY 0.659574 (-1015 3085);
PAINT MONO (-1015 3085);
DISPLAY INVISIBLE (-1015 3085);
FORCEPROP 1 LASTPIN (-1025 3075) BN 13
J 2
(-1013 3083);
DISPLAY 0.680851 (-1013 3083);
PAINT GREEN (-1013 3083);
FORCEPROP 2 LAST CDS_LIB standard
J 0
(-1075 3075);
DISPLAY INVISIBLE (-1075 3075);
FORCEPROP 1 LAST BODY_TYPE PLUMBING
J 2
(-1075 3125);
DISPLAY 0.872340 (-1075 3125);
PAINT GREEN (-1075 3125);
DISPLAY INVISIBLE (-1075 3125);
FORCEPROP 1 LAST HDL_TAP TRUE
J 2
(-1400 2950);
DISPLAY 0.872340 (-1400 2950);
DISPLAY INVISIBLE (-1400 2950);
FORCEPROP 1 LAST PATH I73
J 2
(-1073 3075);
DISPLAY 0.872340 (-1073 3075);
PAINT GREEN (-1073 3075);
DISPLAY INVISIBLE (-1073 3075);
FORCEADD TAP..1
R 2
(-1075 3125);
FORCEPROP 3 LASTPIN (-1025 3125) SIG_NAME M_E_CPU1_SA_DQ<14>
J 0
(-1015 3135);
DISPLAY 0.659574 (-1015 3135);
PAINT MONO (-1015 3135);
DISPLAY INVISIBLE (-1015 3135);
FORCEPROP 1 LASTPIN (-1025 3125) BN 14
J 2
(-1013 3133);
DISPLAY 0.680851 (-1013 3133);
PAINT GREEN (-1013 3133);
FORCEPROP 2 LAST CDS_LIB standard
J 0
(-1075 3125);
DISPLAY INVISIBLE (-1075 3125);
FORCEPROP 1 LAST BODY_TYPE PLUMBING
J 2
(-1075 3175);
DISPLAY 0.872340 (-1075 3175);
PAINT GREEN (-1075 3175);
DISPLAY INVISIBLE (-1075 3175);
FORCEPROP 1 LAST HDL_TAP TRUE
J 2
(-1400 3000);
DISPLAY 0.872340 (-1400 3000);
DISPLAY INVISIBLE (-1400 3000);
FORCEPROP 1 LAST PATH I74
J 2
(-1073 3125);
DISPLAY 0.872340 (-1073 3125);
PAINT GREEN (-1073 3125);
DISPLAY INVISIBLE (-1073 3125);
FORCEADD TAP..1
R 2
(-1075 3175);
FORCEPROP 3 LASTPIN (-1025 3175) SIG_NAME M_E_CPU1_SA_DQ<15>
J 0
(-1015 3185);
DISPLAY 0.659574 (-1015 3185);
PAINT MONO (-1015 3185);
DISPLAY INVISIBLE (-1015 3185);
FORCEPROP 1 LASTPIN (-1025 3175) BN 15
J 2
(-1013 3183);
DISPLAY 0.680851 (-1013 3183);
PAINT GREEN (-1013 3183);
FORCEPROP 2 LAST CDS_LIB standard
J 0
(-1075 3175);
DISPLAY INVISIBLE (-1075 3175);
FORCEPROP 1 LAST BODY_TYPE PLUMBING
J 2
(-1075 3225);
DISPLAY 0.872340 (-1075 3225);
PAINT GREEN (-1075 3225);
DISPLAY INVISIBLE (-1075 3225);
FORCEPROP 1 LAST HDL_TAP TRUE
J 2
(-1400 3050);
DISPLAY 0.872340 (-1400 3050);
DISPLAY INVISIBLE (-1400 3050);
FORCEPROP 1 LAST PATH I75
J 2
(-1073 3175);
DISPLAY 0.872340 (-1073 3175);
PAINT GREEN (-1073 3175);
DISPLAY INVISIBLE (-1073 3175);
FORCEADD TAP..1
R 2
(-1075 3225);
FORCEPROP 3 LASTPIN (-1025 3225) SIG_NAME M_E_CPU1_SA_DQ<16>
J 0
(-1015 3235);
DISPLAY 0.659574 (-1015 3235);
PAINT MONO (-1015 3235);
DISPLAY INVISIBLE (-1015 3235);
FORCEPROP 1 LASTPIN (-1025 3225) BN 16
J 2
(-1013 3233);
DISPLAY 0.680851 (-1013 3233);
PAINT GREEN (-1013 3233);
FORCEPROP 2 LAST CDS_LIB standard
J 0
(-1075 3225);
DISPLAY INVISIBLE (-1075 3225);
FORCEPROP 1 LAST BODY_TYPE PLUMBING
J 2
(-1075 3275);
DISPLAY 0.872340 (-1075 3275);
PAINT GREEN (-1075 3275);
DISPLAY INVISIBLE (-1075 3275);
FORCEPROP 1 LAST HDL_TAP TRUE
J 2
(-1400 3100);
DISPLAY 0.872340 (-1400 3100);
DISPLAY INVISIBLE (-1400 3100);
FORCEPROP 1 LAST PATH I76
J 2
(-1073 3225);
DISPLAY 0.872340 (-1073 3225);
PAINT GREEN (-1073 3225);
DISPLAY INVISIBLE (-1073 3225);
FORCEADD TAP..1
R 2
(-1075 3275);
FORCEPROP 3 LASTPIN (-1025 3275) SIG_NAME M_E_CPU1_SA_DQ<17>
J 0
(-1015 3285);
DISPLAY 0.659574 (-1015 3285);
PAINT MONO (-1015 3285);
DISPLAY INVISIBLE (-1015 3285);
FORCEPROP 1 LASTPIN (-1025 3275) BN 17
J 2
(-1013 3283);
DISPLAY 0.680851 (-1013 3283);
PAINT GREEN (-1013 3283);
FORCEPROP 2 LAST CDS_LIB standard
J 0
(-1075 3275);
DISPLAY INVISIBLE (-1075 3275);
FORCEPROP 1 LAST BODY_TYPE PLUMBING
J 2
(-1075 3325);
DISPLAY 0.872340 (-1075 3325);
PAINT GREEN (-1075 3325);
DISPLAY INVISIBLE (-1075 3325);
FORCEPROP 1 LAST HDL_TAP TRUE
J 2
(-1400 3150);
DISPLAY 0.872340 (-1400 3150);
DISPLAY INVISIBLE (-1400 3150);
FORCEPROP 1 LAST PATH I77
J 2
(-1073 3275);
DISPLAY 0.872340 (-1073 3275);
PAINT GREEN (-1073 3275);
DISPLAY INVISIBLE (-1073 3275);
FORCEADD TAP..1
R 2
(-1075 3375);
FORCEPROP 3 LASTPIN (-1025 3375) SIG_NAME M_E_CPU1_SA_DQ<19>
J 0
(-1015 3385);
DISPLAY 0.659574 (-1015 3385);
PAINT MONO (-1015 3385);
DISPLAY INVISIBLE (-1015 3385);
FORCEPROP 1 LASTPIN (-1025 3375) BN 19
J 2
(-1013 3383);
DISPLAY 0.680851 (-1013 3383);
PAINT GREEN (-1013 3383);
FORCEPROP 2 LAST CDS_LIB standard
J 0
(-1075 3375);
DISPLAY INVISIBLE (-1075 3375);
FORCEPROP 1 LAST BODY_TYPE PLUMBING
J 2
(-1075 3425);
DISPLAY 0.872340 (-1075 3425);
PAINT GREEN (-1075 3425);
DISPLAY INVISIBLE (-1075 3425);
FORCEPROP 1 LAST HDL_TAP TRUE
J 2
(-1400 3250);
DISPLAY 0.872340 (-1400 3250);
DISPLAY INVISIBLE (-1400 3250);
FORCEPROP 1 LAST PATH I78
J 2
(-1073 3375);
DISPLAY 0.872340 (-1073 3375);
PAINT GREEN (-1073 3375);
DISPLAY INVISIBLE (-1073 3375);
FORCEADD TAP..1
R 2
(-1075 3325);
FORCEPROP 3 LASTPIN (-1025 3325) SIG_NAME M_E_CPU1_SA_DQ<18>
J 0
(-1015 3335);
DISPLAY 0.659574 (-1015 3335);
PAINT MONO (-1015 3335);
DISPLAY INVISIBLE (-1015 3335);
FORCEPROP 1 LASTPIN (-1025 3325) BN 18
J 2
(-1013 3333);
DISPLAY 0.680851 (-1013 3333);
PAINT GREEN (-1013 3333);
FORCEPROP 2 LAST CDS_LIB standard
J 0
(-1075 3325);
DISPLAY INVISIBLE (-1075 3325);
FORCEPROP 1 LAST BODY_TYPE PLUMBING
J 2
(-1075 3375);
DISPLAY 0.872340 (-1075 3375);
PAINT GREEN (-1075 3375);
DISPLAY INVISIBLE (-1075 3375);
FORCEPROP 1 LAST HDL_TAP TRUE
J 2
(-1400 3200);
DISPLAY 0.872340 (-1400 3200);
DISPLAY INVISIBLE (-1400 3200);
FORCEPROP 1 LAST PATH I79
J 2
(-1073 3325);
DISPLAY 0.872340 (-1073 3325);
PAINT GREEN (-1073 3325);
DISPLAY INVISIBLE (-1073 3325);
FORCEADD OFFPAGE..3
R 2
(-2100 400);
FORCEPROP 2 LAST $XR1 107 
J 0
(-2530 400);
DISPLAY 0.638298 (-2530 400);
PAINT MONO (-2530 400);
FORCEPROP 2 LAST $XR0 106 
J 0
(-2410 400);
DISPLAY 0.638298 (-2410 400);
PAINT MONO (-2410 400);
FORCEPROP 2 LAST CDS_LIB standard
J 0
(-2100 400);
DISPLAY INVISIBLE (-2100 400);
FORCEPROP 1 LAST OFFPAGE TRUE
J 2
(-2425 275);
DISPLAY 0.872340 (-2425 275);
DISPLAY INVISIBLE (-2425 275);
FORCEPROP 1 LAST COMMENT_BODY TRUE
J 2
(-2050 300);
DISPLAY 0.872340 (-2050 300);
PAINT GREEN (-2050 300);
DISPLAY INVISIBLE (-2050 300);
FORCEPROP 2 LAST PATH I8
J 0
(-2050 475);
DISPLAY 1.021277 (-2050 475);
DISPLAY INVISIBLE (-2050 475);
FORCEADD TAP..1
R 2
(-1075 3425);
FORCEPROP 3 LASTPIN (-1025 3425) SIG_NAME M_E_CPU1_SA_DQ<20>
J 0
(-1015 3435);
DISPLAY 0.659574 (-1015 3435);
PAINT MONO (-1015 3435);
DISPLAY INVISIBLE (-1015 3435);
FORCEPROP 1 LASTPIN (-1025 3425) BN 20
J 2
(-1013 3433);
DISPLAY 0.680851 (-1013 3433);
PAINT GREEN (-1013 3433);
FORCEPROP 2 LAST CDS_LIB standard
J 0
(-1075 3425);
DISPLAY INVISIBLE (-1075 3425);
FORCEPROP 1 LAST BODY_TYPE PLUMBING
J 2
(-1075 3475);
DISPLAY 0.872340 (-1075 3475);
PAINT GREEN (-1075 3475);
DISPLAY INVISIBLE (-1075 3475);
FORCEPROP 1 LAST HDL_TAP TRUE
J 2
(-1400 3300);
DISPLAY 0.872340 (-1400 3300);
DISPLAY INVISIBLE (-1400 3300);
FORCEPROP 1 LAST PATH I80
J 2
(-1073 3425);
DISPLAY 0.872340 (-1073 3425);
PAINT GREEN (-1073 3425);
DISPLAY INVISIBLE (-1073 3425);
FORCEADD TAP..1
R 2
(-1075 3475);
FORCEPROP 3 LASTPIN (-1025 3475) SIG_NAME M_E_CPU1_SA_DQ<21>
J 0
(-1015 3485);
DISPLAY 0.659574 (-1015 3485);
PAINT MONO (-1015 3485);
DISPLAY INVISIBLE (-1015 3485);
FORCEPROP 1 LASTPIN (-1025 3475) BN 21
J 2
(-1013 3483);
DISPLAY 0.680851 (-1013 3483);
PAINT GREEN (-1013 3483);
FORCEPROP 2 LAST CDS_LIB standard
J 0
(-1075 3475);
DISPLAY INVISIBLE (-1075 3475);
FORCEPROP 1 LAST BODY_TYPE PLUMBING
J 2
(-1075 3525);
DISPLAY 0.872340 (-1075 3525);
PAINT GREEN (-1075 3525);
DISPLAY INVISIBLE (-1075 3525);
FORCEPROP 1 LAST HDL_TAP TRUE
J 2
(-1400 3350);
DISPLAY 0.872340 (-1400 3350);
DISPLAY INVISIBLE (-1400 3350);
FORCEPROP 1 LAST PATH I81
J 2
(-1073 3475);
DISPLAY 0.872340 (-1073 3475);
PAINT GREEN (-1073 3475);
DISPLAY INVISIBLE (-1073 3475);
FORCEADD TAP..1
R 2
(-1075 3525);
FORCEPROP 3 LASTPIN (-1025 3525) SIG_NAME M_E_CPU1_SA_DQ<22>
J 0
(-1015 3535);
DISPLAY 0.659574 (-1015 3535);
PAINT MONO (-1015 3535);
DISPLAY INVISIBLE (-1015 3535);
FORCEPROP 1 LASTPIN (-1025 3525) BN 22
J 2
(-1013 3533);
DISPLAY 0.680851 (-1013 3533);
PAINT GREEN (-1013 3533);
FORCEPROP 2 LAST CDS_LIB standard
J 0
(-1075 3525);
DISPLAY INVISIBLE (-1075 3525);
FORCEPROP 1 LAST BODY_TYPE PLUMBING
J 2
(-1075 3575);
DISPLAY 0.872340 (-1075 3575);
PAINT GREEN (-1075 3575);
DISPLAY INVISIBLE (-1075 3575);
FORCEPROP 1 LAST HDL_TAP TRUE
J 2
(-1400 3400);
DISPLAY 0.872340 (-1400 3400);
DISPLAY INVISIBLE (-1400 3400);
FORCEPROP 1 LAST PATH I82
J 2
(-1073 3525);
DISPLAY 0.872340 (-1073 3525);
PAINT GREEN (-1073 3525);
DISPLAY INVISIBLE (-1073 3525);
FORCEADD TAP..1
R 2
(-1075 3575);
FORCEPROP 3 LASTPIN (-1025 3575) SIG_NAME M_E_CPU1_SA_DQ<23>
J 0
(-1015 3585);
DISPLAY 0.659574 (-1015 3585);
PAINT MONO (-1015 3585);
DISPLAY INVISIBLE (-1015 3585);
FORCEPROP 1 LASTPIN (-1025 3575) BN 23
J 2
(-1013 3583);
DISPLAY 0.680851 (-1013 3583);
PAINT GREEN (-1013 3583);
FORCEPROP 2 LAST CDS_LIB standard
J 0
(-1075 3575);
DISPLAY INVISIBLE (-1075 3575);
FORCEPROP 1 LAST BODY_TYPE PLUMBING
J 2
(-1075 3625);
DISPLAY 0.872340 (-1075 3625);
PAINT GREEN (-1075 3625);
DISPLAY INVISIBLE (-1075 3625);
FORCEPROP 1 LAST HDL_TAP TRUE
J 2
(-1400 3450);
DISPLAY 0.872340 (-1400 3450);
DISPLAY INVISIBLE (-1400 3450);
FORCEPROP 1 LAST PATH I83
J 2
(-1073 3575);
DISPLAY 0.872340 (-1073 3575);
PAINT GREEN (-1073 3575);
DISPLAY INVISIBLE (-1073 3575);
FORCEADD TAP..1
R 2
(-1075 3625);
FORCEPROP 3 LASTPIN (-1025 3625) SIG_NAME M_E_CPU1_SA_DQ<24>
J 0
(-1015 3635);
DISPLAY 0.659574 (-1015 3635);
PAINT MONO (-1015 3635);
DISPLAY INVISIBLE (-1015 3635);
FORCEPROP 1 LASTPIN (-1025 3625) BN 24
J 2
(-1013 3633);
DISPLAY 0.680851 (-1013 3633);
PAINT GREEN (-1013 3633);
FORCEPROP 2 LAST CDS_LIB standard
J 0
(-1075 3625);
DISPLAY INVISIBLE (-1075 3625);
FORCEPROP 1 LAST BODY_TYPE PLUMBING
J 2
(-1075 3675);
DISPLAY 0.872340 (-1075 3675);
PAINT GREEN (-1075 3675);
DISPLAY INVISIBLE (-1075 3675);
FORCEPROP 1 LAST HDL_TAP TRUE
J 2
(-1400 3500);
DISPLAY 0.872340 (-1400 3500);
DISPLAY INVISIBLE (-1400 3500);
FORCEPROP 1 LAST PATH I84
J 2
(-1073 3625);
DISPLAY 0.872340 (-1073 3625);
PAINT GREEN (-1073 3625);
DISPLAY INVISIBLE (-1073 3625);
FORCEADD TAP..1
R 2
(-1075 3675);
FORCEPROP 3 LASTPIN (-1025 3675) SIG_NAME M_E_CPU1_SA_DQ<25>
J 0
(-1015 3685);
DISPLAY 0.659574 (-1015 3685);
PAINT MONO (-1015 3685);
DISPLAY INVISIBLE (-1015 3685);
FORCEPROP 1 LASTPIN (-1025 3675) BN 25
J 2
(-1013 3683);
DISPLAY 0.680851 (-1013 3683);
PAINT GREEN (-1013 3683);
FORCEPROP 2 LAST CDS_LIB standard
J 0
(-1075 3675);
DISPLAY INVISIBLE (-1075 3675);
FORCEPROP 1 LAST BODY_TYPE PLUMBING
J 2
(-1075 3725);
DISPLAY 0.872340 (-1075 3725);
PAINT GREEN (-1075 3725);
DISPLAY INVISIBLE (-1075 3725);
FORCEPROP 1 LAST HDL_TAP TRUE
J 2
(-1400 3550);
DISPLAY 0.872340 (-1400 3550);
DISPLAY INVISIBLE (-1400 3550);
FORCEPROP 1 LAST PATH I85
J 2
(-1073 3675);
DISPLAY 0.872340 (-1073 3675);
PAINT GREEN (-1073 3675);
DISPLAY INVISIBLE (-1073 3675);
FORCEADD TAP..1
R 2
(-1075 3725);
FORCEPROP 3 LASTPIN (-1025 3725) SIG_NAME M_E_CPU1_SA_DQ<26>
J 0
(-1015 3735);
DISPLAY 0.659574 (-1015 3735);
PAINT MONO (-1015 3735);
DISPLAY INVISIBLE (-1015 3735);
FORCEPROP 1 LASTPIN (-1025 3725) BN 26
J 2
(-1013 3733);
DISPLAY 0.680851 (-1013 3733);
PAINT GREEN (-1013 3733);
FORCEPROP 2 LAST CDS_LIB standard
J 0
(-1075 3725);
DISPLAY INVISIBLE (-1075 3725);
FORCEPROP 1 LAST BODY_TYPE PLUMBING
J 2
(-1075 3775);
DISPLAY 0.872340 (-1075 3775);
PAINT GREEN (-1075 3775);
DISPLAY INVISIBLE (-1075 3775);
FORCEPROP 1 LAST HDL_TAP TRUE
J 2
(-1400 3600);
DISPLAY 0.872340 (-1400 3600);
DISPLAY INVISIBLE (-1400 3600);
FORCEPROP 1 LAST PATH I86
J 2
(-1073 3725);
DISPLAY 0.872340 (-1073 3725);
PAINT GREEN (-1073 3725);
DISPLAY INVISIBLE (-1073 3725);
FORCEADD TAP..1
R 2
(-1075 3775);
FORCEPROP 3 LASTPIN (-1025 3775) SIG_NAME M_E_CPU1_SA_DQ<27>
J 0
(-1015 3785);
DISPLAY 0.659574 (-1015 3785);
PAINT MONO (-1015 3785);
DISPLAY INVISIBLE (-1015 3785);
FORCEPROP 1 LASTPIN (-1025 3775) BN 27
J 2
(-1013 3783);
DISPLAY 0.680851 (-1013 3783);
PAINT GREEN (-1013 3783);
FORCEPROP 2 LAST CDS_LIB standard
J 0
(-1075 3775);
DISPLAY INVISIBLE (-1075 3775);
FORCEPROP 1 LAST BODY_TYPE PLUMBING
J 2
(-1075 3825);
DISPLAY 0.872340 (-1075 3825);
PAINT GREEN (-1075 3825);
DISPLAY INVISIBLE (-1075 3825);
FORCEPROP 1 LAST HDL_TAP TRUE
J 2
(-1400 3650);
DISPLAY 0.872340 (-1400 3650);
DISPLAY INVISIBLE (-1400 3650);
FORCEPROP 1 LAST PATH I87
J 2
(-1073 3775);
DISPLAY 0.872340 (-1073 3775);
PAINT GREEN (-1073 3775);
DISPLAY INVISIBLE (-1073 3775);
FORCEADD TAP..1
R 2
(-1075 3875);
FORCEPROP 3 LASTPIN (-1025 3875) SIG_NAME M_E_CPU1_SA_DQ<29>
J 0
(-1015 3885);
DISPLAY 0.659574 (-1015 3885);
PAINT MONO (-1015 3885);
DISPLAY INVISIBLE (-1015 3885);
FORCEPROP 1 LASTPIN (-1025 3875) BN 29
J 2
(-1013 3883);
DISPLAY 0.680851 (-1013 3883);
PAINT GREEN (-1013 3883);
FORCEPROP 2 LAST CDS_LIB standard
J 0
(-1075 3875);
DISPLAY INVISIBLE (-1075 3875);
FORCEPROP 1 LAST BODY_TYPE PLUMBING
J 2
(-1075 3925);
DISPLAY 0.872340 (-1075 3925);
PAINT GREEN (-1075 3925);
DISPLAY INVISIBLE (-1075 3925);
FORCEPROP 1 LAST HDL_TAP TRUE
J 2
(-1400 3750);
DISPLAY 0.872340 (-1400 3750);
DISPLAY INVISIBLE (-1400 3750);
FORCEPROP 1 LAST PATH I88
J 2
(-1073 3875);
DISPLAY 0.872340 (-1073 3875);
PAINT GREEN (-1073 3875);
DISPLAY INVISIBLE (-1073 3875);
FORCEADD TAP..1
R 2
(-1075 3825);
FORCEPROP 3 LASTPIN (-1025 3825) SIG_NAME M_E_CPU1_SA_DQ<28>
J 0
(-1015 3835);
DISPLAY 0.659574 (-1015 3835);
PAINT MONO (-1015 3835);
DISPLAY INVISIBLE (-1015 3835);
FORCEPROP 1 LASTPIN (-1025 3825) BN 28
J 2
(-1013 3833);
DISPLAY 0.680851 (-1013 3833);
PAINT GREEN (-1013 3833);
FORCEPROP 2 LAST CDS_LIB standard
J 0
(-1075 3825);
DISPLAY INVISIBLE (-1075 3825);
FORCEPROP 1 LAST BODY_TYPE PLUMBING
J 2
(-1075 3875);
DISPLAY 0.872340 (-1075 3875);
PAINT GREEN (-1075 3875);
DISPLAY INVISIBLE (-1075 3875);
FORCEPROP 1 LAST HDL_TAP TRUE
J 2
(-1400 3700);
DISPLAY 0.872340 (-1400 3700);
DISPLAY INVISIBLE (-1400 3700);
FORCEPROP 1 LAST PATH I89
J 2
(-1073 3825);
DISPLAY 0.872340 (-1073 3825);
PAINT GREEN (-1073 3825);
DISPLAY INVISIBLE (-1073 3825);
FORCEADD OFFPAGE..3
R 2
(-2100 2000);
FORCEPROP 2 LAST $XR1 107 
J 0
(-2530 2000);
DISPLAY 0.638298 (-2530 2000);
PAINT MONO (-2530 2000);
FORCEPROP 2 LAST $XR0 106 
J 0
(-2410 2000);
DISPLAY 0.638298 (-2410 2000);
PAINT MONO (-2410 2000);
FORCEPROP 2 LAST CDS_LIB standard
J 0
(-2100 2000);
DISPLAY INVISIBLE (-2100 2000);
FORCEPROP 1 LAST OFFPAGE TRUE
J 2
(-2425 1875);
DISPLAY 0.872340 (-2425 1875);
DISPLAY INVISIBLE (-2425 1875);
FORCEPROP 1 LAST COMMENT_BODY TRUE
J 2
(-2050 1900);
DISPLAY 0.872340 (-2050 1900);
PAINT GREEN (-2050 1900);
DISPLAY INVISIBLE (-2050 1900);
FORCEPROP 2 LAST PATH I9
J 0
(-2050 2075);
DISPLAY 1.021277 (-2050 2075);
DISPLAY INVISIBLE (-2050 2075);
FORCEADD TAP..1
R 2
(-1075 3925);
FORCEPROP 3 LASTPIN (-1025 3925) SIG_NAME M_E_CPU1_SA_DQ<30>
J 0
(-1015 3935);
DISPLAY 0.659574 (-1015 3935);
PAINT MONO (-1015 3935);
DISPLAY INVISIBLE (-1015 3935);
FORCEPROP 1 LASTPIN (-1025 3925) BN 30
J 2
(-1013 3933);
DISPLAY 0.680851 (-1013 3933);
PAINT GREEN (-1013 3933);
FORCEPROP 2 LAST CDS_LIB standard
J 0
(-1075 3925);
DISPLAY INVISIBLE (-1075 3925);
FORCEPROP 1 LAST BODY_TYPE PLUMBING
J 2
(-1075 3975);
DISPLAY 0.872340 (-1075 3975);
PAINT GREEN (-1075 3975);
DISPLAY INVISIBLE (-1075 3975);
FORCEPROP 1 LAST HDL_TAP TRUE
J 2
(-1400 3800);
DISPLAY 0.872340 (-1400 3800);
DISPLAY INVISIBLE (-1400 3800);
FORCEPROP 1 LAST PATH I90
J 2
(-1073 3925);
DISPLAY 0.872340 (-1073 3925);
PAINT GREEN (-1073 3925);
DISPLAY INVISIBLE (-1073 3925);
FORCEADD TAP..1
R 2
(-1075 3975);
FORCEPROP 3 LASTPIN (-1025 3975) SIG_NAME M_E_CPU1_SA_DQ<31>
J 0
(-1015 3985);
DISPLAY 0.659574 (-1015 3985);
PAINT MONO (-1015 3985);
DISPLAY INVISIBLE (-1015 3985);
FORCEPROP 1 LASTPIN (-1025 3975) BN 31
J 2
(-1013 3983);
DISPLAY 0.680851 (-1013 3983);
PAINT GREEN (-1013 3983);
FORCEPROP 2 LAST CDS_LIB standard
J 0
(-1075 3975);
DISPLAY INVISIBLE (-1075 3975);
FORCEPROP 1 LAST BODY_TYPE PLUMBING
J 2
(-1075 4025);
DISPLAY 0.872340 (-1075 4025);
PAINT GREEN (-1075 4025);
DISPLAY INVISIBLE (-1075 4025);
FORCEPROP 1 LAST HDL_TAP TRUE
J 2
(-1400 3850);
DISPLAY 0.872340 (-1400 3850);
DISPLAY INVISIBLE (-1400 3850);
FORCEPROP 1 LAST PATH I91
J 2
(-1073 3975);
DISPLAY 0.872340 (-1073 3975);
PAINT GREEN (-1073 3975);
DISPLAY INVISIBLE (-1073 3975);
FORCEADD OFFPAGE..4
(3450 -225);
FORCEPROP 2 LAST $XR1 107 
J 0
(3756 -225);
DISPLAY 0.638298 (3756 -225);
PAINT MONO (3756 -225);
FORCEPROP 2 LAST $XR0 106 
J 0
(3636 -225);
DISPLAY 0.638298 (3636 -225);
PAINT MONO (3636 -225);
FORCEPROP 2 LAST CDS_LIB standard
J 0
(3450 -225);
PAINT MONO (3450 -225);
DISPLAY INVISIBLE (3450 -225);
FORCEPROP 1 LAST OFFPAGE TRUE
J 0
(3775 -350);
DISPLAY 1.170213 (3775 -350);
PAINT GREEN (3775 -350);
DISPLAY INVISIBLE (3775 -350);
FORCEPROP 1 LAST COMMENT_BODY TRUE
J 0
(3425 -325);
DISPLAY 1.170213 (3425 -325);
PAINT GREEN (3425 -325);
DISPLAY INVISIBLE (3425 -325);
FORCEPROP 2 LAST PATH I92
J 0
(3625 -150);
DISPLAY 1.021277 (3625 -150);
DISPLAY INVISIBLE (3625 -150);
FORCEADD OFFPAGE..4
(3450 -75);
FORCEPROP 2 LAST $XR0 107 
J 0
(3636 -75);
DISPLAY 0.638298 (3636 -75);
PAINT MONO (3636 -75);
FORCEPROP 2 LAST CDS_LIB standard
J 0
(3450 -75);
PAINT MONO (3450 -75);
DISPLAY INVISIBLE (3450 -75);
FORCEPROP 1 LAST OFFPAGE TRUE
J 0
(3775 -200);
DISPLAY 1.170213 (3775 -200);
PAINT GREEN (3775 -200);
DISPLAY INVISIBLE (3775 -200);
FORCEPROP 1 LAST COMMENT_BODY TRUE
J 0
(3425 -175);
DISPLAY 1.170213 (3425 -175);
PAINT GREEN (3425 -175);
DISPLAY INVISIBLE (3425 -175);
FORCEPROP 2 LAST PATH I93
J 0
(3625 0);
DISPLAY 1.021277 (3625 0);
DISPLAY INVISIBLE (3625 0);
FORCEADD OFFPAGE..4
(3450 -125);
FORCEPROP 2 LAST $XR0 106 
J 0
(3636 -125);
DISPLAY 0.638298 (3636 -125);
PAINT MONO (3636 -125);
FORCEPROP 2 LAST CDS_LIB standard
J 0
(3450 -125);
PAINT MONO (3450 -125);
DISPLAY INVISIBLE (3450 -125);
FORCEPROP 1 LAST OFFPAGE TRUE
J 0
(3775 -250);
DISPLAY 1.170213 (3775 -250);
PAINT GREEN (3775 -250);
DISPLAY INVISIBLE (3775 -250);
FORCEPROP 1 LAST COMMENT_BODY TRUE
J 0
(3425 -225);
DISPLAY 1.170213 (3425 -225);
PAINT GREEN (3425 -225);
DISPLAY INVISIBLE (3425 -225);
FORCEPROP 2 LAST PATH I94
J 0
(3625 -50);
DISPLAY 1.021277 (3625 -50);
DISPLAY INVISIBLE (3625 -50);
FORCEADD TAP..1
(2350 225);
FORCEPROP 3 LASTPIN (2300 225) SIG_NAME M_E_CPU1_SB_CS_N<0>
J 0
(2310 235);
DISPLAY 0.659574 (2310 235);
PAINT MONO (2310 235);
DISPLAY INVISIBLE (2310 235);
FORCEPROP 1 LASTPIN (2300 225) BN 0
J 0
(2288 233);
DISPLAY 0.680851 (2288 233);
PAINT GREEN (2288 233);
FORCEPROP 2 LAST CDS_LIB standard
J 0
(2350 225);
DISPLAY INVISIBLE (2350 225);
FORCEPROP 1 LAST BODY_TYPE PLUMBING
J 0
(2350 275);
DISPLAY 0.872340 (2350 275);
PAINT GREEN (2350 275);
DISPLAY INVISIBLE (2350 275);
FORCEPROP 1 LAST HDL_TAP TRUE
J 0
(2675 100);
DISPLAY 0.872340 (2675 100);
DISPLAY INVISIBLE (2675 100);
FORCEPROP 1 LAST PATH I95
J 0
(2348 225);
DISPLAY 0.872340 (2348 225);
PAINT GREEN (2348 225);
DISPLAY INVISIBLE (2348 225);
FORCEADD TAP..1
(2350 325);
FORCEPROP 3 LASTPIN (2300 325) SIG_NAME M_E_CPU1_SB_CS_N<2>
J 0
(2310 335);
DISPLAY 0.659574 (2310 335);
PAINT MONO (2310 335);
DISPLAY INVISIBLE (2310 335);
FORCEPROP 1 LASTPIN (2300 325) BN 2
J 0
(2288 333);
DISPLAY 0.680851 (2288 333);
PAINT GREEN (2288 333);
FORCEPROP 2 LAST CDS_LIB standard
J 0
(2350 325);
DISPLAY INVISIBLE (2350 325);
FORCEPROP 1 LAST BODY_TYPE PLUMBING
J 0
(2350 375);
DISPLAY 0.872340 (2350 375);
PAINT GREEN (2350 375);
DISPLAY INVISIBLE (2350 375);
FORCEPROP 1 LAST HDL_TAP TRUE
J 0
(2675 200);
DISPLAY 0.872340 (2675 200);
DISPLAY INVISIBLE (2675 200);
FORCEPROP 1 LAST PATH I96
J 0
(2348 325);
DISPLAY 0.872340 (2348 325);
PAINT GREEN (2348 325);
DISPLAY INVISIBLE (2348 325);
FORCEADD TAP..1
(2350 275);
FORCEPROP 3 LASTPIN (2300 275) SIG_NAME M_E_CPU1_SB_CS_N<1>
J 0
(2310 285);
DISPLAY 0.659574 (2310 285);
PAINT MONO (2310 285);
DISPLAY INVISIBLE (2310 285);
FORCEPROP 1 LASTPIN (2300 275) BN 1
J 0
(2288 283);
DISPLAY 0.680851 (2288 283);
PAINT GREEN (2288 283);
FORCEPROP 2 LAST CDS_LIB standard
J 0
(2350 275);
DISPLAY INVISIBLE (2350 275);
FORCEPROP 1 LAST BODY_TYPE PLUMBING
J 0
(2350 325);
DISPLAY 0.872340 (2350 325);
PAINT GREEN (2350 325);
DISPLAY INVISIBLE (2350 325);
FORCEPROP 1 LAST HDL_TAP TRUE
J 0
(2675 150);
DISPLAY 0.872340 (2675 150);
DISPLAY INVISIBLE (2675 150);
FORCEPROP 1 LAST PATH I97
J 0
(2348 275);
DISPLAY 0.872340 (2348 275);
PAINT GREEN (2348 275);
DISPLAY INVISIBLE (2348 275);
FORCEADD TAP..1
(2350 375);
FORCEPROP 3 LASTPIN (2300 375) SIG_NAME M_E_CPU1_SB_CS_N<3>
J 0
(2310 385);
DISPLAY 0.659574 (2310 385);
PAINT MONO (2310 385);
DISPLAY INVISIBLE (2310 385);
FORCEPROP 1 LASTPIN (2300 375) BN 3
J 0
(2288 383);
DISPLAY 0.680851 (2288 383);
PAINT GREEN (2288 383);
FORCEPROP 2 LAST CDS_LIB standard
J 0
(2350 375);
DISPLAY INVISIBLE (2350 375);
FORCEPROP 1 LAST BODY_TYPE PLUMBING
J 0
(2350 425);
DISPLAY 0.872340 (2350 425);
PAINT GREEN (2350 425);
DISPLAY INVISIBLE (2350 425);
FORCEPROP 1 LAST HDL_TAP TRUE
J 0
(2675 250);
DISPLAY 0.872340 (2675 250);
DISPLAY INVISIBLE (2675 250);
FORCEPROP 1 LAST PATH I98
J 0
(2348 375);
DISPLAY 0.872340 (2348 375);
PAINT GREEN (2348 375);
DISPLAY INVISIBLE (2348 375);
FORCEADD TAP..1
(2350 625);
FORCEPROP 3 LASTPIN (2300 625) SIG_NAME M_E_CPU1_SA_CS_N<2>
J 0
(2310 635);
DISPLAY 0.659574 (2310 635);
PAINT MONO (2310 635);
DISPLAY INVISIBLE (2310 635);
FORCEPROP 1 LASTPIN (2300 625) BN 2
J 0
(2288 633);
DISPLAY 0.680851 (2288 633);
PAINT GREEN (2288 633);
FORCEPROP 2 LAST CDS_LIB standard
J 0
(2350 625);
DISPLAY INVISIBLE (2350 625);
FORCEPROP 1 LAST BODY_TYPE PLUMBING
J 0
(2350 675);
DISPLAY 0.872340 (2350 675);
PAINT GREEN (2350 675);
DISPLAY INVISIBLE (2350 675);
FORCEPROP 1 LAST HDL_TAP TRUE
J 0
(2675 500);
DISPLAY 0.872340 (2675 500);
DISPLAY INVISIBLE (2675 500);
FORCEPROP 1 LAST PATH I99
J 0
(2348 625);
DISPLAY 0.872340 (2348 625);
PAINT GREEN (2348 625);
DISPLAY INVISIBLE (2348 625);
FORCEADD QUANTA_TITLE_BLOCK_C..1
(5275 -1525);
FORCEPROP 0 LAST CDS_CON_LAST_MODIFIED Fri Aug 25 14:00:37 2023
J 0
(3390 -1510);
PAINT MONO (3390 -1510);
DISPLAY INVISIBLE (3390 -1510);
FORCEPROP 2 LAST CUSTOM_TXT_CDS <XR_PAGE_TITLE>
J 0
(-2615 3725);
DISPLAY 0.638298 (-2615 3725);
PAINT PINK (-2615 3725);
DISPLAY INVISIBLE (-2615 3725);
FORCEPROP 2 LAST CUSTOM_TXT_CDS <CON_LAST_MODIFIED>
J 0
(3400 -1500);
DISPLAY 0.978723 (3400 -1500);
FORCEPROP 2 LAST CUSTOM_TXT_CDS <Q_NUMBER>
J 0
(3872 -1422);
DISPLAY 1.212766 (3872 -1422);
FORCEPROP 2 LAST CUSTOM_TXT_CDS <CON_PAGE_NUM> OF <CON_TOTAL_PAGES>
J 0
(4829 -1507);
DISPLAY 0.978723 (4829 -1507);
FORCEPROP 2 LAST CUSTOM_TXT_CDS <NAME_2>
J 0
(2100 -1475);
FORCEPROP 2 LAST CUSTOM_TXT_CDS <NAME_1>
J 0
(2100 -1350);
FORCEPROP 2 LAST CUSTOM_TXT_CDS <Q_PROJ>
J 0
(2893 -1423);
DISPLAY 1.212766 (2893 -1423);
FORCEPROP 2 LAST CUSTOM_TXT_CDS <Q_REV>
J 0
(5091 -1422);
DISPLAY 1.212766 (5091 -1422);
FORCEPROP 1 LAST Q_TITLE SPR CPU1 - DDR CH E (12 OF 30)
J 0
(-4091 -1499);
DISPLAY 1.957447 (-4091 -1499);
PAINT GREEN (-4091 -1499);
FORCEPROP 1 LAST Q_DEPT 
J 1
(1512 -1476);
DISPLAY 1.957447 (1512 -1476);
PAINT GREEN (1512 -1476);
FORCEPROP 1 LAST COMMENT_BODY TRUE
J 0
(5287 -1538);
DISPLAY 0.978723 (5287 -1538);
PAINT GREEN (5287 -1538);
DISPLAY INVISIBLE (5287 -1538);
FORCEPROP 2 LAST CDS_XR_PAGE_TITLE CR-55 : @S9S_MB_2U_LIB.S9S_MB_2U(SCH_1):PAGE55
J 0
(-2615 3725);
DISPLAY 0.638298 (-2615 3725);
PAINT PINK (-2615 3725);
DISPLAY INVISIBLE (-2615 3725);
FORCEPROP 2 LAST CDS_LIB pure_quanta
J 0
(5275 -1525);
PAINT MONO (5275 -1525);
DISPLAY INVISIBLE (5275 -1525);
FORCEPROP 1 LAST CDS_LMAN_SYM_OUTLINE -9475,6775,100,-125
J 0
(5275 -1525);
DISPLAY 0.468085 (5275 -1525);
PAINT GREEN (5275 -1525);
DISPLAY INVISIBLE (5275 -1525);
FORCEPROP 2 LAST PAGE_BORDER TRUE
J 0
(-2615 3725);
DISPLAY 0.638298 (-2615 3725);
PAINT PINK (-2615 3725);
DISPLAY INVISIBLE (-2615 3725);
WIRE 17 -1 (2400 1700)(3400 1700);
FORCEPROP 2 LAST SIG_NAME M_E_CPU1_SA_CA<6:0>
J 0
(2540 1710);
DISPLAY 0.680851 (2540 1710);
PAINT WHITE (2540 1710);
WIRE 17 -1 (2400 1650)(2400 1700);
WIRE 17 -1 (2400 1600)(2400 1650);
WIRE 17 -1 (2400 1550)(2400 1600);
WIRE 17 -1 (2400 1500)(2400 1550);
WIRE 17 -1 (2400 1450)(2400 1500);
WIRE 17 -1 (2400 1400)(2400 1450);
WIRE 17 -1 (2400 700)(3400 700);
FORCEPROP 2 LAST SIG_NAME M_E_CPU1_SA_CS_N<3:0>
J 0
(2540 710);
DISPLAY 0.680851 (2540 710);
PAINT WHITE (2540 710);
WIRE 17 -1 (2400 650)(2400 700);
WIRE 17 -1 (2400 600)(2400 650);
WIRE 17 -1 (2400 550)(2400 600);
WIRE 17 -1 (2400 3450)(3400 3450);
FORCEPROP 2 LAST SIG_NAME M_E_CPU1_SA_DQS_DN<9:0>
J 0
(2540 3460);
DISPLAY 0.680851 (2540 3460);
PAINT WHITE (2540 3460);
WIRE 17 -1 (2400 3400)(2400 3450);
WIRE 17 -1 (2400 3350)(2400 3400);
WIRE 17 -1 (2400 3300)(2400 3350);
WIRE 17 -1 (2400 3250)(2400 3300);
WIRE 17 -1 (2400 3200)(2400 3250);
WIRE 17 -1 (2400 3150)(2400 3200);
WIRE 17 -1 (2400 3100)(2400 3150);
WIRE 17 -1 (2400 3050)(2400 3100);
WIRE 17 -1 (2400 3000)(2400 3050);
WIRE 17 -1 (2400 4000)(3400 4000);
FORCEPROP 2 LAST SIG_NAME M_E_CPU1_SA_DQS_DP<9:0>
J 0
(2540 4010);
DISPLAY 0.680851 (2540 4010);
PAINT WHITE (2540 4010);
WIRE 17 -1 (2400 3950)(2400 4000);
WIRE 17 -1 (2400 3900)(2400 3950);
WIRE 17 -1 (2400 3850)(2400 3900);
WIRE 17 -1 (2400 3800)(2400 3850);
WIRE 17 -1 (2400 3750)(2400 3800);
WIRE 17 -1 (2400 3700)(2400 3750);
WIRE 17 -1 (2400 3650)(2400 3700);
WIRE 17 -1 (2400 3600)(2400 3650);
WIRE 17 -1 (2400 3550)(2400 3600);
WIRE 17 -1 (2400 1200)(3400 1200);
FORCEPROP 2 LAST SIG_NAME M_E_CPU1_SB_CA<6:0>
J 0
(2540 1210);
DISPLAY 0.680851 (2540 1210);
PAINT WHITE (2540 1210);
WIRE 17 -1 (2400 1150)(2400 1200);
WIRE 17 -1 (2400 1100)(2400 1150);
WIRE 17 -1 (2400 1050)(2400 1100);
WIRE 17 -1 (2400 1000)(2400 1050);
WIRE 17 -1 (2400 950)(2400 1000);
WIRE 17 -1 (2400 900)(2400 950);
WIRE 17 -1 (2400 400)(3400 400);
FORCEPROP 2 LAST SIG_NAME M_E_CPU1_SB_CS_N<3:0>
J 0
(2540 410);
DISPLAY 0.680851 (2540 410);
PAINT WHITE (2540 410);
WIRE 17 -1 (2400 350)(2400 400);
WIRE 17 -1 (2400 300)(2400 350);
WIRE 17 -1 (2400 250)(2400 300);
WIRE 17 -1 (2400 2300)(3400 2300);
FORCEPROP 2 LAST SIG_NAME M_E_CPU1_SB_DQS_DN<9:0>
J 0
(2540 2310);
DISPLAY 0.680851 (2540 2310);
PAINT WHITE (2540 2310);
WIRE 17 -1 (2400 2250)(2400 2300);
WIRE 17 -1 (2400 2200)(2400 2250);
WIRE 17 -1 (2400 2150)(2400 2200);
WIRE 17 -1 (2400 2100)(2400 2150);
WIRE 17 -1 (2400 2050)(2400 2100);
WIRE 17 -1 (2400 2000)(2400 2050);
WIRE 17 -1 (2400 1950)(2400 2000);
WIRE 17 -1 (2400 1900)(2400 1950);
WIRE 17 -1 (2400 1850)(2400 1900);
WIRE 17 -1 (2400 2850)(3400 2850);
FORCEPROP 2 LAST SIG_NAME M_E_CPU1_SB_DQS_DP<9:0>
J 0
(2540 2860);
DISPLAY 0.680851 (2540 2860);
PAINT WHITE (2540 2860);
WIRE 17 -1 (2400 2800)(2400 2850);
WIRE 17 -1 (2400 2750)(2400 2800);
WIRE 17 -1 (2400 2700)(2400 2750);
WIRE 17 -1 (2400 2650)(2400 2700);
WIRE 17 -1 (2400 2600)(2400 2650);
WIRE 17 -1 (2400 2550)(2400 2600);
WIRE 17 -1 (2400 2500)(2400 2550);
WIRE 17 -1 (2400 2450)(2400 2500);
WIRE 17 -1 (2400 2400)(2400 2450);
WIRE 17 -1 (-1125 50)(-1125 100);
WIRE 17 -1 (-1125 100)(-1125 150);
WIRE 17 -1 (-1125 150)(-1125 200);
WIRE 17 -1 (-1125 200)(-1125 250);
WIRE 17 -1 (-1125 250)(-1125 300);
WIRE 17 -1 (-1125 300)(-1125 350);
WIRE 17 -1 (-1125 350)(-1125 400);
WIRE 17 -1 (-2050 400)(-1125 400);
FORCEPROP 2 LAST SIG_NAME M_E_CPU1_SB_CB<7:0>
J 0
(-1910 410);
DISPLAY 0.680851 (-1910 410);
PAINT WHITE (-1910 410);
WIRE 17 -1 (-1125 450)(-1125 500);
WIRE 17 -1 (-1125 500)(-1125 550);
WIRE 17 -1 (-1125 550)(-1125 600);
WIRE 17 -1 (-1125 600)(-1125 650);
WIRE 17 -1 (-1125 650)(-1125 700);
WIRE 17 -1 (-1125 700)(-1125 750);
WIRE 17 -1 (-1125 750)(-1125 800);
WIRE 17 -1 (-1125 800)(-1125 850);
WIRE 17 -1 (-1125 850)(-1125 900);
WIRE 17 -1 (-1125 900)(-1125 950);
WIRE 17 -1 (-1125 950)(-1125 1000);
WIRE 17 -1 (-1125 1000)(-1125 1050);
WIRE 17 -1 (-1125 1050)(-1125 1100);
WIRE 17 -1 (-1125 1100)(-1125 1150);
WIRE 17 -1 (-1125 1150)(-1125 1200);
WIRE 17 -1 (-1125 1200)(-1125 1250);
WIRE 17 -1 (-1125 1250)(-1125 1300);
WIRE 17 -1 (-1125 1300)(-1125 1350);
WIRE 17 -1 (-1125 1350)(-1125 1400);
WIRE 17 -1 (-1125 1400)(-1125 1450);
WIRE 17 -1 (-1125 1450)(-1125 1500);
WIRE 17 -1 (-1125 1500)(-1125 1550);
WIRE 17 -1 (-1125 1550)(-1125 1600);
WIRE 17 -1 (-1125 1600)(-1125 1650);
WIRE 17 -1 (-1125 1650)(-1125 1700);
WIRE 17 -1 (-1125 1700)(-1125 1750);
WIRE 17 -1 (-1125 1750)(-1125 1800);
WIRE 17 -1 (-1125 1800)(-1125 1850);
WIRE 17 -1 (-1125 1850)(-1125 1900);
WIRE 17 -1 (-1125 1900)(-1125 1950);
WIRE 17 -1 (-1125 1950)(-1125 2000);
WIRE 17 -1 (-2050 2000)(-1125 2000);
FORCEPROP 2 LAST SIG_NAME M_E_CPU1_SB_DQ<31:0>
J 0
(-1910 2010);
DISPLAY 0.680851 (-1910 2010);
PAINT WHITE (-1910 2010);
WIRE 17 -1 (-1125 2050)(-1125 2100);
WIRE 17 -1 (-1125 2100)(-1125 2150);
WIRE 17 -1 (-1125 2150)(-1125 2200);
WIRE 17 -1 (-1125 2200)(-1125 2250);
WIRE 17 -1 (-1125 2250)(-1125 2300);
WIRE 17 -1 (-1125 2300)(-1125 2350);
WIRE 17 -1 (-1125 2350)(-1125 2400);
WIRE 17 -1 (-2050 2400)(-1125 2400);
FORCEPROP 2 LAST SIG_NAME M_E_CPU1_SA_CB<7:0>
J 0
(-1910 2410);
DISPLAY 0.680851 (-1910 2410);
PAINT WHITE (-1910 2410);
WIRE 17 -1 (-1125 2450)(-1125 2500);
WIRE 17 -1 (-1125 2500)(-1125 2550);
WIRE 17 -1 (-1125 2550)(-1125 2600);
WIRE 17 -1 (-1125 2600)(-1125 2650);
WIRE 17 -1 (-1125 2650)(-1125 2700);
WIRE 17 -1 (-1125 2700)(-1125 2750);
WIRE 17 -1 (-1125 2750)(-1125 2800);
WIRE 17 -1 (-1125 2800)(-1125 2850);
WIRE 17 -1 (-1125 2850)(-1125 2900);
WIRE 17 -1 (-1125 2900)(-1125 2950);
WIRE 17 -1 (-1125 2950)(-1125 3000);
WIRE 17 -1 (-1125 3000)(-1125 3050);
WIRE 17 -1 (-1125 3050)(-1125 3100);
WIRE 17 -1 (-1125 3100)(-1125 3150);
WIRE 17 -1 (-1125 3150)(-1125 3200);
WIRE 17 -1 (-1125 3200)(-1125 3250);
WIRE 17 -1 (-1125 3250)(-1125 3300);
WIRE 17 -1 (-1125 3300)(-1125 3350);
WIRE 17 -1 (-1125 3350)(-1125 3400);
WIRE 17 -1 (-1125 3400)(-1125 3450);
WIRE 17 -1 (-1125 3450)(-1125 3500);
WIRE 17 -1 (-1125 3500)(-1125 3550);
WIRE 17 -1 (-1125 3550)(-1125 3600);
WIRE 17 -1 (-1125 3600)(-1125 3650);
WIRE 17 -1 (-1125 3650)(-1125 3700);
WIRE 17 -1 (-1125 3700)(-1125 3750);
WIRE 17 -1 (-1125 3750)(-1125 3800);
WIRE 17 -1 (-1125 3800)(-1125 3850);
WIRE 17 -1 (-1125 3850)(-1125 3900);
WIRE 17 -1 (-1125 3900)(-1125 3950);
WIRE 17 -1 (-1125 3950)(-1125 4000);
WIRE 17 -1 (-2050 4000)(-1125 4000);
FORCEPROP 2 LAST SIG_NAME M_E_CPU1_SA_DQ<31:0>
J 0
(-1910 4010);
DISPLAY 0.680851 (-1910 4010);
PAINT WHITE (-1910 4010);
WIRE 17 -1 (-1125 -100)(-1125 -50);
WIRE 17 -1 (-2050 -50)(-1125 -50);
FORCEPROP 2 LAST SIG_NAME M_E_CPU1_CLK_DP<1:0>
J 0
(-1910 -40);
DISPLAY 0.680851 (-1910 -40);
PAINT WHITE (-1910 -40);
WIRE 17 -1 (-1125 -200)(-1125 -150);
WIRE 17 -1 (-2050 -150)(-1125 -150);
FORCEPROP 2 LAST SIG_NAME M_E_CPU1_CLK_DN<1:0>
J 0
(-1910 -140);
DISPLAY 0.680851 (-1910 -140);
PAINT WHITE (-1910 -140);
WIRE 16 -1 (-1025 2775)(-575 2775);
WIRE 16 -1 (-1025 2725)(-575 2725);
WIRE 16 -1 (-1025 2675)(-575 2675);
WIRE 16 -1 (-1025 -175)(-575 -175);
WIRE 16 -1 (-1025 -225)(-575 -225);
WIRE 16 -1 (-1025 -75)(-575 -75);
WIRE 16 -1 (-1025 -125)(-575 -125);
WIRE 16 -1 (-1025 3975)(-575 3975);
WIRE 16 -1 (-1025 3925)(-575 3925);
WIRE 16 -1 (-1025 3875)(-575 3875);
WIRE 16 -1 (-1025 3825)(-575 3825);
WIRE 16 -1 (-1025 3775)(-575 3775);
WIRE 16 -1 (-1025 3725)(-575 3725);
WIRE 16 -1 (-1025 3675)(-575 3675);
WIRE 16 -1 (-1025 3625)(-575 3625);
WIRE 16 -1 (-1025 3575)(-575 3575);
WIRE 16 -1 (-1025 3525)(-575 3525);
WIRE 16 -1 (-1025 3475)(-575 3475);
WIRE 16 -1 (-1025 3425)(-575 3425);
WIRE 16 -1 (-1025 3375)(-575 3375);
WIRE 16 -1 (-1025 3325)(-575 3325);
WIRE 16 -1 (-1025 3275)(-575 3275);
WIRE 16 -1 (-1025 3225)(-575 3225);
WIRE 16 -1 (-1025 3175)(-575 3175);
WIRE 16 -1 (-1025 3125)(-575 3125);
WIRE 16 -1 (-1025 3075)(-575 3075);
WIRE 16 -1 (-1025 3025)(-575 3025);
WIRE 16 -1 (-1025 2975)(-575 2975);
WIRE 16 -1 (-1025 2925)(-575 2925);
WIRE 16 -1 (-1025 2875)(-575 2875);
WIRE 16 -1 (-1025 2825)(-575 2825);
WIRE 16 -1 (-1025 2625)(-575 2625);
WIRE 16 -1 (-1025 2575)(-575 2575);
WIRE 16 -1 (-1025 2525)(-575 2525);
WIRE 16 -1 (-1025 2475)(-575 2475);
WIRE 16 -1 (-1025 2425)(-575 2425);
WIRE 16 -1 (-1025 2375)(-575 2375);
WIRE 16 -1 (-1025 2325)(-575 2325);
WIRE 16 -1 (-1025 2275)(-575 2275);
WIRE 16 -1 (-1025 2225)(-575 2225);
WIRE 16 -1 (-1025 2175)(-575 2175);
WIRE 16 -1 (-1025 2125)(-575 2125);
WIRE 16 -1 (-1025 2075)(-575 2075);
WIRE 16 -1 (-1025 2025)(-575 2025);
WIRE 16 -1 (-1025 1975)(-575 1975);
WIRE 16 -1 (-1025 1925)(-575 1925);
WIRE 16 -1 (-1025 1875)(-575 1875);
WIRE 16 -1 (-1025 1825)(-575 1825);
WIRE 16 -1 (-1025 1775)(-575 1775);
WIRE 16 -1 (-1025 1725)(-575 1725);
WIRE 16 -1 (-1025 1675)(-575 1675);
WIRE 16 -1 (-1025 1625)(-575 1625);
WIRE 16 -1 (-1025 1575)(-575 1575);
WIRE 16 -1 (-1025 1525)(-575 1525);
WIRE 16 -1 (-1025 1475)(-575 1475);
WIRE 16 -1 (-1025 1425)(-575 1425);
WIRE 16 -1 (-1025 1375)(-575 1375);
WIRE 16 -1 (-1025 1325)(-575 1325);
WIRE 16 -1 (-1025 1275)(-575 1275);
WIRE 16 -1 (-1025 1225)(-575 1225);
WIRE 16 -1 (-1025 1175)(-575 1175);
WIRE 16 -1 (-1025 1125)(-575 1125);
WIRE 16 -1 (-1025 1075)(-575 1075);
WIRE 16 -1 (-1025 1025)(-575 1025);
WIRE 16 -1 (-1025 975)(-575 975);
WIRE 16 -1 (-1025 925)(-575 925);
WIRE 16 -1 (-1025 875)(-575 875);
WIRE 16 -1 (-1025 825)(-575 825);
WIRE 16 -1 (-1025 775)(-575 775);
WIRE 16 -1 (-1025 725)(-575 725);
WIRE 16 -1 (-1025 675)(-575 675);
WIRE 16 -1 (-1025 625)(-575 625);
WIRE 16 -1 (-1025 575)(-575 575);
WIRE 16 -1 (-1025 525)(-575 525);
WIRE 16 -1 (-1025 475)(-575 475);
WIRE 16 -1 (-1025 425)(-575 425);
WIRE 16 -1 (-1025 375)(-575 375);
WIRE 16 -1 (-1025 325)(-575 325);
WIRE 16 -1 (-1025 275)(-575 275);
WIRE 16 -1 (-1025 225)(-575 225);
WIRE 16 -1 (-1025 175)(-575 175);
WIRE 16 -1 (-1025 125)(-575 125);
WIRE 16 -1 (-1025 75)(-575 75);
WIRE 16 -1 (-1025 25)(-575 25);
WIRE 16 -1 (3400 825)(1875 825);
FORCEPROP 2 LAST SIG_NAME M_E_CPU1_SB_PAR
J 0
(2509 834);
DISPLAY 0.680851 (2509 834);
PAINT WHITE (2509 834);
WIRE 16 -1 (1875 2375)(2300 2375);
WIRE 16 -1 (1875 2425)(2300 2425);
WIRE 16 -1 (1875 2475)(2300 2475);
WIRE 16 -1 (1875 2525)(2300 2525);
WIRE 16 -1 (1875 2575)(2300 2575);
WIRE 16 -1 (1875 2625)(2300 2625);
WIRE 16 -1 (1875 2675)(2300 2675);
WIRE 16 -1 (1875 2725)(2300 2725);
WIRE 16 -1 (1875 2775)(2300 2775);
WIRE 16 -1 (1875 2825)(2300 2825);
WIRE 16 -1 (1875 1825)(2300 1825);
WIRE 16 -1 (1875 1875)(2300 1875);
WIRE 16 -1 (1875 1925)(2300 1925);
WIRE 16 -1 (1875 1975)(2300 1975);
WIRE 16 -1 (1875 2025)(2300 2025);
WIRE 16 -1 (1875 2075)(2300 2075);
WIRE 16 -1 (1875 2125)(2300 2125);
WIRE 16 -1 (1875 2175)(2300 2175);
WIRE 16 -1 (1875 2225)(2300 2225);
WIRE 16 -1 (1875 2275)(2300 2275);
WIRE 16 -1 (1875 225)(2300 225);
WIRE 16 -1 (1875 275)(2300 275);
WIRE 16 -1 (1875 325)(2300 325);
WIRE 16 -1 (1875 375)(2300 375);
WIRE 16 -1 (1875 875)(2300 875);
WIRE 16 -1 (1875 925)(2300 925);
WIRE 16 -1 (1875 975)(2300 975);
WIRE 16 -1 (1875 1025)(2300 1025);
WIRE 16 -1 (1875 1075)(2300 1075);
WIRE 16 -1 (1875 1125)(2300 1125);
WIRE 16 -1 (1875 1175)(2300 1175);
WIRE 16 -1 (3400 1325)(1875 1325);
FORCEPROP 2 LAST SIG_NAME M_E_CPU1_SA_PAR
J 0
(2509 1334);
DISPLAY 0.680851 (2509 1334);
PAINT WHITE (2509 1334);
WIRE 16 -1 (1875 3525)(2300 3525);
WIRE 16 -1 (1875 3575)(2300 3575);
WIRE 16 -1 (1875 3625)(2300 3625);
WIRE 16 -1 (1875 3675)(2300 3675);
WIRE 16 -1 (1875 3725)(2300 3725);
WIRE 16 -1 (1875 3775)(2300 3775);
WIRE 16 -1 (1875 3825)(2300 3825);
WIRE 16 -1 (1875 3875)(2300 3875);
WIRE 16 -1 (1875 3925)(2300 3925);
WIRE 16 -1 (1875 3975)(2300 3975);
WIRE 16 -1 (1875 2975)(2300 2975);
WIRE 16 -1 (1875 3025)(2300 3025);
WIRE 16 -1 (1875 3075)(2300 3075);
WIRE 16 -1 (1875 3125)(2300 3125);
WIRE 16 -1 (1875 3175)(2300 3175);
WIRE 16 -1 (1875 3225)(2300 3225);
WIRE 16 -1 (1875 3275)(2300 3275);
WIRE 16 -1 (1875 3325)(2300 3325);
WIRE 16 -1 (1875 3375)(2300 3375);
WIRE 16 -1 (1875 3425)(2300 3425);
WIRE 16 -1 (1875 525)(2300 525);
WIRE 16 -1 (1875 575)(2300 575);
WIRE 16 -1 (1875 625)(2300 625);
WIRE 16 -1 (1875 675)(2300 675);
WIRE 16 -1 (1875 1375)(2300 1375);
WIRE 16 -1 (1875 1425)(2300 1425);
WIRE 16 -1 (1875 1475)(2300 1475);
WIRE 16 -1 (1875 1525)(2300 1525);
WIRE 16 -1 (1875 1575)(2300 1575);
WIRE 16 -1 (1875 1625)(2300 1625);
WIRE 16 -1 (1875 1675)(2300 1675);
WIRE 16 -1 (3400 -125)(1875 -125);
FORCEPROP 2 LAST SIG_NAME M_E_CPU1_SB_RSP<0>
J 0
(2509 -116);
DISPLAY 0.680851 (2509 -116);
PAINT WHITE (2509 -116);
WIRE 16 -1 (3400 -75)(1875 -75);
FORCEPROP 2 LAST SIG_NAME M_E_CPU1_SB_RSP<1>
J 0
(2509 -66);
DISPLAY 0.680851 (2509 -66);
PAINT WHITE (2509 -66);
WIRE 16 -1 (3400 25)(1875 25);
FORCEPROP 2 LAST SIG_NAME M_E_CPU1_SA_RSP<0>
J 0
(2509 34);
DISPLAY 0.680851 (2509 34);
PAINT WHITE (2509 34);
WIRE 16 -1 (3400 75)(1875 75);
FORCEPROP 2 LAST SIG_NAME M_E_CPU1_SA_RSP<1>
J 0
(2509 84);
DISPLAY 0.680851 (2509 84);
PAINT WHITE (2509 84);
WIRE 16 -1 (3400 -225)(1875 -225);
FORCEPROP 2 LAST SIG_NAME M_E_CPU1_ALERT_N
J 0
(2509 -216);
DISPLAY 0.680851 (2509 -216);
PAINT WHITE (2509 -216);
QUIT
